(kicad_sch
	(version 20250114)
	(generator "eeschema")
	(generator_version "9.0")
	(paper "A3")
	(title_block
		(title "COM Express 7 Baseboard")
		(date "2025-02-04")
		(rev "1.1.2")
		(company "Antmicro Ltd")
		(comment 1 "www.antmicro.com")
	)
	(bus_alias ""
		(members)
	)
	(bus_alias "PCIe_{REF}"
		(members "CK+" "CK-")
	)
	(text "LX2160 SERDES CONFIGURATION:\nSD1 = 3\nSD2 = 3\nSD3 = 3"
		(exclude_from_sim no)
		(at 320.04 180.34 0)
		(effects
			(font
				(size 1.27 1.27)
			)
			(justify left bottom)
		)
	)
	(text "COM Express 7 interfaces"
		(exclude_from_sim no)
		(at 184.404 19.05 0)
		(effects
			(font
				(size 2 2)
				(thickness 0.4)
				(bold yes)
			)
			(justify left bottom)
		)
	)
	(text "Can be x4"
		(exclude_from_sim no)
		(at 92.71 217.17 0)
		(effects
			(font
				(size 1.27 1.27)
			)
			(justify left bottom)
		)
	)
	(junction
		(at 246.38 259.08)
		(diameter 0)
		(color 0 0 0 0)
	)
	(junction
		(at 246.38 252.73)
		(diameter 0)
		(color 0 0 0 0)
	)
	(junction
		(at 246.38 265.43)
		(diameter 0)
		(color 0 0 0 0)
	)
	(junction
		(at 246.38 271.78)
		(diameter 0)
		(color 0 0 0 0)
	)
	(no_connect
		(at 281.94 55.88)
	)
	(no_connect
		(at 210.82 251.46)
	)
	(no_connect
		(at 68.58 165.1)
	)
	(no_connect
		(at 281.94 147.32)
	)
	(no_connect
		(at 281.94 58.42)
	)
	(no_connect
		(at 139.7 177.8)
	)
	(no_connect
		(at 68.58 223.52)
	)
	(no_connect
		(at 68.58 66.04)
	)
	(no_connect
		(at 355.6 43.18)
	)
	(no_connect
		(at 68.58 208.28)
	)
	(no_connect
		(at 210.82 246.38)
	)
	(no_connect
		(at 210.82 243.84)
	)
	(no_connect
		(at 281.94 149.86)
	)
	(no_connect
		(at 68.58 50.8)
	)
	(no_connect
		(at 68.58 132.08)
	)
	(no_connect
		(at 68.58 134.62)
	)
	(no_connect
		(at 68.58 35.56)
	)
	(no_connect
		(at 139.7 182.88)
	)
	(no_connect
		(at 281.94 144.78)
	)
	(no_connect
		(at 68.58 93.98)
	)
	(no_connect
		(at 355.6 48.26)
	)
	(no_connect
		(at 68.58 157.48)
	)
	(no_connect
		(at 281.94 220.98)
	)
	(no_connect
		(at 139.7 193.04)
	)
	(no_connect
		(at 139.7 190.5)
	)
	(no_connect
		(at 68.58 185.42)
	)
	(no_connect
		(at 281.94 40.64)
	)
	(no_connect
		(at 68.58 180.34)
	)
	(no_connect
		(at 139.7 259.08)
	)
	(no_connect
		(at 68.58 200.66)
	)
	(no_connect
		(at 281.94 134.62)
	)
	(no_connect
		(at 68.58 81.28)
	)
	(no_connect
		(at 281.94 200.66)
	)
	(no_connect
		(at 355.6 58.42)
	)
	(no_connect
		(at 68.58 43.18)
	)
	(no_connect
		(at 68.58 162.56)
	)
	(no_connect
		(at 281.94 215.9)
	)
	(no_connect
		(at 68.58 177.8)
	)
	(no_connect
		(at 68.58 139.7)
	)
	(no_connect
		(at 68.58 210.82)
	)
	(no_connect
		(at 68.58 55.88)
	)
	(no_connect
		(at 281.94 218.44)
	)
	(no_connect
		(at 210.82 236.22)
	)
	(no_connect
		(at 68.58 215.9)
	)
	(no_connect
		(at 210.82 261.62)
	)
	(no_connect
		(at 68.58 149.86)
	)
	(no_connect
		(at 139.7 248.92)
	)
	(no_connect
		(at 210.82 238.76)
	)
	(no_connect
		(at 281.94 139.7)
	)
	(no_connect
		(at 68.58 233.68)
	)
	(no_connect
		(at 68.58 172.72)
	)
	(no_connect
		(at 68.58 86.36)
	)
	(no_connect
		(at 281.94 43.18)
	)
	(no_connect
		(at 281.94 157.48)
	)
	(no_connect
		(at 68.58 48.26)
	)
	(no_connect
		(at 68.58 238.76)
	)
	(no_connect
		(at 355.6 35.56)
	)
	(no_connect
		(at 281.94 162.56)
	)
	(no_connect
		(at 355.6 55.88)
	)
	(no_connect
		(at 281.94 50.8)
	)
	(no_connect
		(at 139.7 167.64)
	)
	(no_connect
		(at 281.94 35.56)
	)
	(no_connect
		(at 68.58 203.2)
	)
	(no_connect
		(at 68.58 231.14)
	)
	(no_connect
		(at 281.94 208.28)
	)
	(no_connect
		(at 139.7 175.26)
	)
	(no_connect
		(at 68.58 63.5)
	)
	(no_connect
		(at 68.58 226.06)
	)
	(no_connect
		(at 68.58 119.38)
	)
	(no_connect
		(at 68.58 71.12)
	)
	(no_connect
		(at 68.58 78.74)
	)
	(no_connect
		(at 139.7 185.42)
	)
	(no_connect
		(at 68.58 73.66)
	)
	(no_connect
		(at 281.94 132.08)
	)
	(no_connect
		(at 210.82 259.08)
	)
	(no_connect
		(at 68.58 96.52)
	)
	(no_connect
		(at 68.58 195.58)
	)
	(no_connect
		(at 68.58 109.22)
	)
	(no_connect
		(at 281.94 203.2)
	)
	(no_connect
		(at 281.94 154.94)
	)
	(no_connect
		(at 355.6 63.5)
	)
	(no_connect
		(at 210.82 254)
	)
	(no_connect
		(at 281.94 198.12)
	)
	(no_connect
		(at 281.94 165.1)
	)
	(no_connect
		(at 68.58 142.24)
	)
	(no_connect
		(at 281.94 142.24)
	)
	(no_connect
		(at 281.94 213.36)
	)
	(no_connect
		(at 68.58 116.84)
	)
	(no_connect
		(at 68.58 241.3)
	)
	(no_connect
		(at 139.7 170.18)
	)
	(no_connect
		(at 68.58 58.42)
	)
	(no_connect
		(at 68.58 101.6)
	)
	(no_connect
		(at 281.94 210.82)
	)
	(no_connect
		(at 281.94 160.02)
	)
	(no_connect
		(at 281.94 205.74)
	)
	(no_connect
		(at 68.58 218.44)
	)
	(no_connect
		(at 68.58 88.9)
	)
	(no_connect
		(at 68.58 147.32)
	)
	(no_connect
		(at 355.6 40.64)
	)
	(no_connect
		(at 281.94 48.26)
	)
	(no_connect
		(at 68.58 33.02)
	)
	(no_connect
		(at 68.58 154.94)
	)
	(no_connect
		(at 68.58 111.76)
	)
	(no_connect
		(at 355.6 33.02)
	)
	(no_connect
		(at 68.58 170.18)
	)
	(no_connect
		(at 68.58 193.04)
	)
	(no_connect
		(at 68.58 104.14)
	)
	(no_connect
		(at 355.6 50.8)
	)
	(no_connect
		(at 281.94 33.02)
	)
	(no_connect
		(at 68.58 127)
	)
	(no_connect
		(at 68.58 124.46)
	)
	(no_connect
		(at 68.58 40.64)
	)
	(no_connect
		(at 210.82 190.5)
	)
	(no_connect
		(at 68.58 187.96)
	)
	(bus_entry
		(at 219.71 180.34)
		(size 1.27 -1.27)
		(stroke
			(width 0)
			(type default)
		)
	)
	(bus_entry
		(at 154.94 101.6)
		(size 1.27 -1.27)
		(stroke
			(width 0)
			(type default)
		)
	)
	(bus_entry
		(at 154.94 147.32)
		(size 1.27 -1.27)
		(stroke
			(width 0)
			(type default)
		)
	)
	(bus_entry
		(at 228.6 111.76)
		(size 1.27 -1.27)
		(stroke
			(width 0)
			(type default)
		)
	)
	(bus_entry
		(at 373.38 92.71)
		(size -1.27 1.27)
		(stroke
			(width 0)
			(type default)
		)
	)
	(bus_entry
		(at 154.94 134.62)
		(size 1.27 -1.27)
		(stroke
			(width 0)
			(type default)
		)
	)
	(bus_entry
		(at 228.6 58.42)
		(size 1.27 -1.27)
		(stroke
			(width 0)
			(type default)
		)
	)
	(bus_entry
		(at 290.83 86.36)
		(size 1.27 -1.27)
		(stroke
			(width 0)
			(type default)
		)
	)
	(bus_entry
		(at 154.94 124.46)
		(size 1.27 -1.27)
		(stroke
			(width 0)
			(type default)
		)
	)
	(bus_entry
		(at 224.79 208.28)
		(size 1.27 -1.27)
		(stroke
			(width 0)
			(type default)
		)
	)
	(bus_entry
		(at 86.36 256.54)
		(size 1.27 -1.27)
		(stroke
			(width 0)
			(type default)
		)
	)
	(bus_entry
		(at 299.72 120.65)
		(size -1.27 1.27)
		(stroke
			(width 0)
			(type default)
		)
	)
	(bus_entry
		(at 290.83 71.12)
		(size 1.27 -1.27)
		(stroke
			(width 0)
			(type default)
		)
	)
	(bus_entry
		(at 373.38 74.93)
		(size -1.27 1.27)
		(stroke
			(width 0)
			(type default)
		)
	)
	(bus_entry
		(at 228.6 86.36)
		(size 1.27 -1.27)
		(stroke
			(width 0)
			(type default)
		)
	)
	(bus_entry
		(at 228.6 104.14)
		(size 1.27 -1.27)
		(stroke
			(width 0)
			(type default)
		)
	)
	(bus_entry
		(at 154.94 109.22)
		(size 1.27 -1.27)
		(stroke
			(width 0)
			(type default)
		)
	)
	(bus_entry
		(at 224.79 231.14)
		(size 1.27 -1.27)
		(stroke
			(width 0)
			(type default)
		)
	)
	(bus_entry
		(at 154.94 132.08)
		(size 1.27 -1.27)
		(stroke
			(width 0)
			(type default)
		)
	)
	(bus_entry
		(at 151.13 218.44)
		(size 1.27 -1.27)
		(stroke
			(width 0)
			(type default)
		)
	)
	(bus_entry
		(at 86.36 254)
		(size 1.27 -1.27)
		(stroke
			(width 0)
			(type default)
		)
	)
	(bus_entry
		(at 86.36 261.62)
		(size 1.27 -1.27)
		(stroke
			(width 0)
			(type default)
		)
	)
	(bus_entry
		(at 154.94 127)
		(size 1.27 -1.27)
		(stroke
			(width 0)
			(type default)
		)
	)
	(bus_entry
		(at 373.38 77.47)
		(size -1.27 1.27)
		(stroke
			(width 0)
			(type default)
		)
	)
	(bus_entry
		(at 154.94 139.7)
		(size 1.27 -1.27)
		(stroke
			(width 0)
			(type default)
		)
	)
	(bus_entry
		(at 228.6 48.26)
		(size 1.27 -1.27)
		(stroke
			(width 0)
			(type default)
		)
	)
	(bus_entry
		(at 154.94 50.8)
		(size 1.27 -1.27)
		(stroke
			(width 0)
			(type default)
		)
	)
	(bus_entry
		(at 86.36 271.78)
		(size 1.27 -1.27)
		(stroke
			(width 0)
			(type default)
		)
	)
	(bus_entry
		(at 224.79 220.98)
		(size 1.27 -1.27)
		(stroke
			(width 0)
			(type default)
		)
	)
	(bus_entry
		(at 224.79 228.6)
		(size 1.27 -1.27)
		(stroke
			(width 0)
			(type default)
		)
	)
	(bus_entry
		(at 228.6 50.8)
		(size 1.27 -1.27)
		(stroke
			(width 0)
			(type default)
		)
	)
	(bus_entry
		(at 224.79 205.74)
		(size 1.27 -1.27)
		(stroke
			(width 0)
			(type default)
		)
	)
	(bus_entry
		(at 299.72 123.19)
		(size -1.27 1.27)
		(stroke
			(width 0)
			(type default)
		)
	)
	(bus_entry
		(at 228.6 63.5)
		(size 1.27 -1.27)
		(stroke
			(width 0)
			(type default)
		)
	)
	(bus_entry
		(at 86.36 246.38)
		(size 1.27 -1.27)
		(stroke
			(width 0)
			(type default)
		)
	)
	(bus_entry
		(at 373.38 90.17)
		(size -1.27 1.27)
		(stroke
			(width 0)
			(type default)
		)
	)
	(bus_entry
		(at 228.6 119.38)
		(size 1.27 -1.27)
		(stroke
			(width 0)
			(type default)
		)
	)
	(bus_entry
		(at 154.94 116.84)
		(size 1.27 -1.27)
		(stroke
			(width 0)
			(type default)
		)
	)
	(bus_entry
		(at 154.94 35.56)
		(size 1.27 -1.27)
		(stroke
			(width 0)
			(type default)
		)
	)
	(bus_entry
		(at 154.94 40.64)
		(size 1.27 -1.27)
		(stroke
			(width 0)
			(type default)
		)
	)
	(bus_entry
		(at 154.94 119.38)
		(size 1.27 -1.27)
		(stroke
			(width 0)
			(type default)
		)
	)
	(bus_entry
		(at 228.6 73.66)
		(size 1.27 -1.27)
		(stroke
			(width 0)
			(type default)
		)
	)
	(bus_entry
		(at 219.71 157.48)
		(size 1.27 -1.27)
		(stroke
			(width 0)
			(type default)
		)
	)
	(bus_entry
		(at 151.13 223.52)
		(size 1.27 -1.27)
		(stroke
			(width 0)
			(type default)
		)
	)
	(bus_entry
		(at 224.79 213.36)
		(size 1.27 -1.27)
		(stroke
			(width 0)
			(type default)
		)
	)
	(bus_entry
		(at 154.94 142.24)
		(size 1.27 -1.27)
		(stroke
			(width 0)
			(type default)
		)
	)
	(bus_entry
		(at 154.94 78.74)
		(size 1.27 -1.27)
		(stroke
			(width 0)
			(type default)
		)
	)
	(bus_entry
		(at 228.6 109.22)
		(size 1.27 -1.27)
		(stroke
			(width 0)
			(type default)
		)
	)
	(bus_entry
		(at 151.13 226.06)
		(size 1.27 -1.27)
		(stroke
			(width 0)
			(type default)
		)
	)
	(bus_entry
		(at 151.13 215.9)
		(size 1.27 -1.27)
		(stroke
			(width 0)
			(type default)
		)
	)
	(bus_entry
		(at 154.94 48.26)
		(size 1.27 -1.27)
		(stroke
			(width 0)
			(type default)
		)
	)
	(bus_entry
		(at 219.71 182.88)
		(size 1.27 -1.27)
		(stroke
			(width 0)
			(type default)
		)
	)
	(bus_entry
		(at 154.94 81.28)
		(size 1.27 -1.27)
		(stroke
			(width 0)
			(type default)
		)
	)
	(bus_entry
		(at 290.83 88.9)
		(size 1.27 -1.27)
		(stroke
			(width 0)
			(type default)
		)
	)
	(bus_entry
		(at 154.94 63.5)
		(size 1.27 -1.27)
		(stroke
			(width 0)
			(type default)
		)
	)
	(bus_entry
		(at 299.72 118.11)
		(size -1.27 1.27)
		(stroke
			(width 0)
			(type default)
		)
	)
	(bus_entry
		(at 299.72 100.33)
		(size -1.27 1.27)
		(stroke
			(width 0)
			(type default)
		)
	)
	(bus_entry
		(at 290.83 81.28)
		(size 1.27 -1.27)
		(stroke
			(width 0)
			(type default)
		)
	)
	(bus_entry
		(at 154.94 111.76)
		(size 1.27 -1.27)
		(stroke
			(width 0)
			(type default)
		)
	)
	(bus_entry
		(at 219.71 175.26)
		(size 1.27 -1.27)
		(stroke
			(width 0)
			(type default)
		)
	)
	(bus_entry
		(at 154.94 58.42)
		(size 1.27 -1.27)
		(stroke
			(width 0)
			(type default)
		)
	)
	(bus_entry
		(at 228.6 81.28)
		(size 1.27 -1.27)
		(stroke
			(width 0)
			(type default)
		)
	)
	(bus_entry
		(at 219.71 167.64)
		(size 1.27 -1.27)
		(stroke
			(width 0)
			(type default)
		)
	)
	(bus_entry
		(at 290.83 73.66)
		(size 1.27 -1.27)
		(stroke
			(width 0)
			(type default)
		)
	)
	(bus_entry
		(at 219.71 160.02)
		(size 1.27 -1.27)
		(stroke
			(width 0)
			(type default)
		)
	)
	(bus_entry
		(at 151.13 233.68)
		(size 1.27 -1.27)
		(stroke
			(width 0)
			(type default)
		)
	)
	(bus_entry
		(at 290.83 66.04)
		(size 1.27 -1.27)
		(stroke
			(width 0)
			(type default)
		)
	)
	(bus_entry
		(at 151.13 241.3)
		(size 1.27 -1.27)
		(stroke
			(width 0)
			(type default)
		)
	)
	(bus_entry
		(at 154.94 73.66)
		(size 1.27 -1.27)
		(stroke
			(width 0)
			(type default)
		)
	)
	(bus_entry
		(at 228.6 78.74)
		(size 1.27 -1.27)
		(stroke
			(width 0)
			(type default)
		)
	)
	(bus_entry
		(at 228.6 127)
		(size 1.27 -1.27)
		(stroke
			(width 0)
			(type default)
		)
	)
	(bus_entry
		(at 154.94 88.9)
		(size 1.27 -1.27)
		(stroke
			(width 0)
			(type default)
		)
	)
	(bus_entry
		(at 373.38 85.09)
		(size -1.27 1.27)
		(stroke
			(width 0)
			(type default)
		)
	)
	(bus_entry
		(at 154.94 93.98)
		(size 1.27 -1.27)
		(stroke
			(width 0)
			(type default)
		)
	)
	(bus_entry
		(at 290.83 78.74)
		(size 1.27 -1.27)
		(stroke
			(width 0)
			(type default)
		)
	)
	(bus_entry
		(at 373.38 87.63)
		(size -1.27 1.27)
		(stroke
			(width 0)
			(type default)
		)
	)
	(bus_entry
		(at 290.83 63.5)
		(size 1.27 -1.27)
		(stroke
			(width 0)
			(type default)
		)
	)
	(bus_entry
		(at 86.36 269.24)
		(size 1.27 -1.27)
		(stroke
			(width 0)
			(type default)
		)
	)
	(bus_entry
		(at 224.79 215.9)
		(size 1.27 -1.27)
		(stroke
			(width 0)
			(type default)
		)
	)
	(bus_entry
		(at 228.6 35.56)
		(size 1.27 -1.27)
		(stroke
			(width 0)
			(type default)
		)
	)
	(bus_entry
		(at 224.79 223.52)
		(size 1.27 -1.27)
		(stroke
			(width 0)
			(type default)
		)
	)
	(bus_entry
		(at 299.72 107.95)
		(size -1.27 1.27)
		(stroke
			(width 0)
			(type default)
		)
	)
	(bus_entry
		(at 228.6 124.46)
		(size 1.27 -1.27)
		(stroke
			(width 0)
			(type default)
		)
	)
	(bus_entry
		(at 228.6 33.02)
		(size 1.27 -1.27)
		(stroke
			(width 0)
			(type default)
		)
	)
	(bus_entry
		(at 219.71 165.1)
		(size 1.27 -1.27)
		(stroke
			(width 0)
			(type default)
		)
	)
	(bus_entry
		(at 154.94 33.02)
		(size 1.27 -1.27)
		(stroke
			(width 0)
			(type default)
		)
	)
	(bus_entry
		(at 228.6 88.9)
		(size 1.27 -1.27)
		(stroke
			(width 0)
			(type default)
		)
	)
	(bus_entry
		(at 154.94 66.04)
		(size 1.27 -1.27)
		(stroke
			(width 0)
			(type default)
		)
	)
	(bus_entry
		(at 151.13 210.82)
		(size 1.27 -1.27)
		(stroke
			(width 0)
			(type default)
		)
	)
	(bus_entry
		(at 154.94 96.52)
		(size 1.27 -1.27)
		(stroke
			(width 0)
			(type default)
		)
	)
	(bus_entry
		(at 228.6 93.98)
		(size 1.27 -1.27)
		(stroke
			(width 0)
			(type default)
		)
	)
	(bus_entry
		(at 151.13 231.14)
		(size 1.27 -1.27)
		(stroke
			(width 0)
			(type default)
		)
	)
	(bus_entry
		(at 228.6 55.88)
		(size 1.27 -1.27)
		(stroke
			(width 0)
			(type default)
		)
	)
	(bus_entry
		(at 228.6 71.12)
		(size 1.27 -1.27)
		(stroke
			(width 0)
			(type default)
		)
	)
	(bus_entry
		(at 299.72 181.61)
		(size -1.27 1.27)
		(stroke
			(width 0)
			(type default)
		)
	)
	(bus_entry
		(at 154.94 86.36)
		(size 1.27 -1.27)
		(stroke
			(width 0)
			(type default)
		)
	)
	(bus_entry
		(at 154.94 71.12)
		(size 1.27 -1.27)
		(stroke
			(width 0)
			(type default)
		)
	)
	(bus_entry
		(at 151.13 238.76)
		(size 1.27 -1.27)
		(stroke
			(width 0)
			(type default)
		)
	)
	(bus_entry
		(at 86.36 264.16)
		(size 1.27 -1.27)
		(stroke
			(width 0)
			(type default)
		)
	)
	(bus_entry
		(at 299.72 102.87)
		(size -1.27 1.27)
		(stroke
			(width 0)
			(type default)
		)
	)
	(bus_entry
		(at 86.36 248.92)
		(size 1.27 -1.27)
		(stroke
			(width 0)
			(type default)
		)
	)
	(bus_entry
		(at 299.72 115.57)
		(size -1.27 1.27)
		(stroke
			(width 0)
			(type default)
		)
	)
	(bus_entry
		(at 228.6 43.18)
		(size 1.27 -1.27)
		(stroke
			(width 0)
			(type default)
		)
	)
	(bus_entry
		(at 219.71 172.72)
		(size 1.27 -1.27)
		(stroke
			(width 0)
			(type default)
		)
	)
	(bus_entry
		(at 154.94 43.18)
		(size 1.27 -1.27)
		(stroke
			(width 0)
			(type default)
		)
	)
	(bus_entry
		(at 154.94 104.14)
		(size 1.27 -1.27)
		(stroke
			(width 0)
			(type default)
		)
	)
	(bus_entry
		(at 154.94 149.86)
		(size 1.27 -1.27)
		(stroke
			(width 0)
			(type default)
		)
	)
	(bus_entry
		(at 228.6 101.6)
		(size 1.27 -1.27)
		(stroke
			(width 0)
			(type default)
		)
	)
	(bus_entry
		(at 228.6 40.64)
		(size 1.27 -1.27)
		(stroke
			(width 0)
			(type default)
		)
	)
	(bus_entry
		(at 228.6 96.52)
		(size 1.27 -1.27)
		(stroke
			(width 0)
			(type default)
		)
	)
	(bus_entry
		(at 154.94 55.88)
		(size 1.27 -1.27)
		(stroke
			(width 0)
			(type default)
		)
	)
	(bus_entry
		(at 299.72 105.41)
		(size -1.27 1.27)
		(stroke
			(width 0)
			(type default)
		)
	)
	(bus_entry
		(at 228.6 66.04)
		(size 1.27 -1.27)
		(stroke
			(width 0)
			(type default)
		)
	)
	(bus_entry
		(at 228.6 116.84)
		(size 1.27 -1.27)
		(stroke
			(width 0)
			(type default)
		)
	)
	(bus_entry
		(at 299.72 184.15)
		(size -1.27 1.27)
		(stroke
			(width 0)
			(type default)
		)
	)
	(bus
		(pts
			(xy 220.98 156.21) (xy 220.98 154.94)
		)
		(stroke
			(width 0)
			(type default)
		)
	)
	(wire
		(pts
			(xy 298.45 109.22) (xy 281.94 109.22)
		)
		(stroke
			(width 0)
			(type default)
		)
	)
	(bus
		(pts
			(xy 229.87 77.47) (xy 229.87 72.39)
		)
		(stroke
			(width 0)
			(type default)
		)
	)
	(wire
		(pts
			(xy 139.7 218.44) (xy 151.13 218.44)
		)
		(stroke
			(width 0)
			(type default)
		)
	)
	(wire
		(pts
			(xy 139.7 43.18) (xy 154.94 43.18)
		)
		(stroke
			(width 0)
			(type default)
		)
	)
	(wire
		(pts
			(xy 210.82 172.72) (xy 219.71 172.72)
		)
		(stroke
			(width 0)
			(type default)
		)
	)
	(wire
		(pts
			(xy 139.7 63.5) (xy 154.94 63.5)
		)
		(stroke
			(width 0)
			(type default)
		)
	)
	(wire
		(pts
			(xy 210.82 66.04) (xy 228.6 66.04)
		)
		(stroke
			(width 0)
			(type default)
		)
	)
	(wire
		(pts
			(xy 210.82 208.28) (xy 224.79 208.28)
		)
		(stroke
			(width 0)
			(type default)
		)
	)
	(wire
		(pts
			(xy 139.7 88.9) (xy 154.94 88.9)
		)
		(stroke
			(width 0)
			(type default)
		)
	)
	(bus
		(pts
			(xy 156.21 91.44) (xy 156.21 92.71)
		)
		(stroke
			(width 0)
			(type default)
		)
	)
	(wire
		(pts
			(xy 210.82 231.14) (xy 224.79 231.14)
		)
		(stroke
			(width 0)
			(type default)
		)
	)
	(bus
		(pts
			(xy 303.53 180.34) (xy 300.99 180.34)
		)
		(stroke
			(width 0)
			(type default)
		)
	)
	(bus
		(pts
			(xy 156.21 130.81) (xy 156.21 133.35)
		)
		(stroke
			(width 0)
			(type default)
		)
	)
	(wire
		(pts
			(xy 139.7 124.46) (xy 154.94 124.46)
		)
		(stroke
			(width 0)
			(type default)
		)
	)
	(bus
		(pts
			(xy 226.06 227.33) (xy 226.06 229.87)
		)
		(stroke
			(width 0)
			(type default)
		)
	)
	(wire
		(pts
			(xy 139.7 226.06) (xy 151.13 226.06)
		)
		(stroke
			(width 0)
			(type default)
		)
	)
	(wire
		(pts
			(xy 139.7 71.12) (xy 154.94 71.12)
		)
		(stroke
			(width 0)
			(type default)
		)
	)
	(wire
		(pts
			(xy 246.38 271.78) (xy 246.38 275.59)
		)
		(stroke
			(width 0)
			(type default)
		)
	)
	(wire
		(pts
			(xy 139.7 96.52) (xy 154.94 96.52)
		)
		(stroke
			(width 0)
			(type default)
		)
	)
	(wire
		(pts
			(xy 139.7 238.76) (xy 151.13 238.76)
		)
		(stroke
			(width 0)
			(type default)
		)
	)
	(bus
		(pts
			(xy 303.53 114.3) (xy 300.99 114.3)
		)
		(stroke
			(width 0)
			(type default)
		)
	)
	(wire
		(pts
			(xy 68.58 271.78) (xy 86.36 271.78)
		)
		(stroke
			(width 0)
			(type default)
		)
	)
	(bus
		(pts
			(xy 220.98 177.8) (xy 220.98 179.07)
		)
		(stroke
			(width 0)
			(type default)
		)
	)
	(wire
		(pts
			(xy 139.7 48.26) (xy 154.94 48.26)
		)
		(stroke
			(width 0)
			(type default)
		)
	)
	(bus
		(pts
			(xy 292.1 85.09) (xy 292.1 80.01)
		)
		(stroke
			(width 0)
			(type default)
		)
	)
	(bus
		(pts
			(xy 87.63 262.89) (xy 87.63 260.35)
		)
		(stroke
			(width 0)
			(type default)
		)
	)
	(bus
		(pts
			(xy 229.87 92.71) (xy 229.87 87.63)
		)
		(stroke
			(width 0)
			(type default)
		)
	)
	(bus
		(pts
			(xy 226.06 219.71) (xy 226.06 222.25)
		)
		(stroke
			(width 0)
			(type default)
		)
	)
	(wire
		(pts
			(xy 210.82 63.5) (xy 228.6 63.5)
		)
		(stroke
			(width 0)
			(type default)
		)
	)
	(wire
		(pts
			(xy 281.94 88.9) (xy 290.83 88.9)
		)
		(stroke
			(width 0)
			(type default)
		)
	)
	(bus
		(pts
			(xy 226.06 222.25) (xy 226.06 227.33)
		)
		(stroke
			(width 0)
			(type default)
		)
	)
	(wire
		(pts
			(xy 210.82 215.9) (xy 224.79 215.9)
		)
		(stroke
			(width 0)
			(type default)
		)
	)
	(wire
		(pts
			(xy 246.38 252.73) (xy 247.65 252.73)
		)
		(stroke
			(width 0)
			(type default)
		)
	)
	(wire
		(pts
			(xy 68.58 269.24) (xy 86.36 269.24)
		)
		(stroke
			(width 0)
			(type default)
		)
	)
	(bus
		(pts
			(xy 220.98 171.45) (xy 220.98 170.18)
		)
		(stroke
			(width 0)
			(type default)
		)
	)
	(wire
		(pts
			(xy 139.7 66.04) (xy 154.94 66.04)
		)
		(stroke
			(width 0)
			(type default)
		)
	)
	(wire
		(pts
			(xy 68.58 256.54) (xy 86.36 256.54)
		)
		(stroke
			(width 0)
			(type default)
		)
	)
	(wire
		(pts
			(xy 246.38 271.78) (xy 247.65 271.78)
		)
		(stroke
			(width 0)
			(type default)
		)
	)
	(wire
		(pts
			(xy 139.7 233.68) (xy 151.13 233.68)
		)
		(stroke
			(width 0)
			(type default)
		)
	)
	(bus
		(pts
			(xy 299.72 115.57) (xy 299.72 118.11)
		)
		(stroke
			(width 0)
			(type default)
		)
	)
	(bus
		(pts
			(xy 87.63 255.27) (xy 87.63 252.73)
		)
		(stroke
			(width 0)
			(type default)
		)
	)
	(wire
		(pts
			(xy 139.7 223.52) (xy 151.13 223.52)
		)
		(stroke
			(width 0)
			(type default)
		)
	)
	(bus
		(pts
			(xy 229.87 41.91) (xy 229.87 39.37)
		)
		(stroke
			(width 0)
			(type default)
		)
	)
	(wire
		(pts
			(xy 139.7 73.66) (xy 154.94 73.66)
		)
		(stroke
			(width 0)
			(type default)
		)
	)
	(bus
		(pts
			(xy 299.72 120.65) (xy 300.99 119.38)
		)
		(stroke
			(width 0)
			(type default)
		)
	)
	(wire
		(pts
			(xy 246.38 259.08) (xy 246.38 265.43)
		)
		(stroke
			(width 0)
			(type default)
		)
	)
	(wire
		(pts
			(xy 139.7 55.88) (xy 154.94 55.88)
		)
		(stroke
			(width 0)
			(type default)
		)
	)
	(wire
		(pts
			(xy 148.59 246.38) (xy 139.7 246.38)
		)
		(stroke
			(width 0)
			(type default)
		)
	)
	(wire
		(pts
			(xy 139.7 132.08) (xy 154.94 132.08)
		)
		(stroke
			(width 0)
			(type default)
		)
	)
	(bus
		(pts
			(xy 156.21 115.57) (xy 156.21 118.11)
		)
		(stroke
			(width 0)
			(type default)
		)
	)
	(wire
		(pts
			(xy 210.82 213.36) (xy 224.79 213.36)
		)
		(stroke
			(width 0)
			(type default)
		)
	)
	(wire
		(pts
			(xy 139.7 50.8) (xy 154.94 50.8)
		)
		(stroke
			(width 0)
			(type default)
		)
	)
	(bus
		(pts
			(xy 229.87 54.61) (xy 229.87 49.53)
		)
		(stroke
			(width 0)
			(type default)
		)
	)
	(wire
		(pts
			(xy 246.38 252.73) (xy 246.38 259.08)
		)
		(stroke
			(width 0)
			(type default)
		)
	)
	(wire
		(pts
			(xy 68.58 261.62) (xy 86.36 261.62)
		)
		(stroke
			(width 0)
			(type default)
		)
	)
	(bus
		(pts
			(xy 373.38 74.93) (xy 373.38 77.47)
		)
		(stroke
			(width 0)
			(type default)
		)
	)
	(bus
		(pts
			(xy 156.21 92.71) (xy 156.21 95.25)
		)
		(stroke
			(width 0)
			(type default)
		)
	)
	(bus
		(pts
			(xy 229.87 49.53) (xy 229.87 46.99)
		)
		(stroke
			(width 0)
			(type default)
		)
	)
	(bus
		(pts
			(xy 156.21 57.15) (xy 156.21 62.23)
		)
		(stroke
			(width 0)
			(type default)
		)
	)
	(wire
		(pts
			(xy 246.38 265.43) (xy 247.65 265.43)
		)
		(stroke
			(width 0)
			(type default)
		)
	)
	(wire
		(pts
			(xy 372.11 91.44) (xy 355.6 91.44)
		)
		(stroke
			(width 0)
			(type default)
		)
	)
	(bus
		(pts
			(xy 220.98 173.99) (xy 220.98 171.45)
		)
		(stroke
			(width 0)
			(type default)
		)
	)
	(wire
		(pts
			(xy 210.82 104.14) (xy 228.6 104.14)
		)
		(stroke
			(width 0)
			(type default)
		)
	)
	(bus
		(pts
			(xy 156.21 77.47) (xy 156.21 80.01)
		)
		(stroke
			(width 0)
			(type default)
		)
	)
	(bus
		(pts
			(xy 87.63 260.35) (xy 87.63 255.27)
		)
		(stroke
			(width 0)
			(type default)
		)
	)
	(bus
		(pts
			(xy 226.06 219.71) (xy 226.06 218.44)
		)
		(stroke
			(width 0)
			(type default)
		)
	)
	(wire
		(pts
			(xy 210.82 182.88) (xy 219.71 182.88)
		)
		(stroke
			(width 0)
			(type default)
		)
	)
	(bus
		(pts
			(xy 303.53 104.14) (xy 300.99 104.14)
		)
		(stroke
			(width 0)
			(type default)
		)
	)
	(wire
		(pts
			(xy 139.7 210.82) (xy 151.13 210.82)
		)
		(stroke
			(width 0)
			(type default)
		)
	)
	(wire
		(pts
			(xy 281.94 78.74) (xy 290.83 78.74)
		)
		(stroke
			(width 0)
			(type default)
		)
	)
	(wire
		(pts
			(xy 139.7 78.74) (xy 154.94 78.74)
		)
		(stroke
			(width 0)
			(type default)
		)
	)
	(wire
		(pts
			(xy 298.45 185.42) (xy 281.94 185.42)
		)
		(stroke
			(width 0)
			(type default)
		)
	)
	(bus
		(pts
			(xy 87.63 252.73) (xy 87.63 247.65)
		)
		(stroke
			(width 0)
			(type default)
		)
	)
	(wire
		(pts
			(xy 210.82 50.8) (xy 228.6 50.8)
		)
		(stroke
			(width 0)
			(type default)
		)
	)
	(wire
		(pts
			(xy 210.82 88.9) (xy 228.6 88.9)
		)
		(stroke
			(width 0)
			(type default)
		)
	)
	(bus
		(pts
			(xy 156.21 34.29) (xy 156.21 39.37)
		)
		(stroke
			(width 0)
			(type default)
		)
	)
	(wire
		(pts
			(xy 210.82 48.26) (xy 228.6 48.26)
		)
		(stroke
			(width 0)
			(type default)
		)
	)
	(bus
		(pts
			(xy 229.87 69.85) (xy 229.87 64.77)
		)
		(stroke
			(width 0)
			(type default)
		)
	)
	(wire
		(pts
			(xy 210.82 35.56) (xy 228.6 35.56)
		)
		(stroke
			(width 0)
			(type default)
		)
	)
	(wire
		(pts
			(xy 139.7 40.64) (xy 154.94 40.64)
		)
		(stroke
			(width 0)
			(type default)
		)
	)
	(bus
		(pts
			(xy 229.87 57.15) (xy 229.87 54.61)
		)
		(stroke
			(width 0)
			(type default)
		)
	)
	(bus
		(pts
			(xy 299.72 115.57) (xy 300.99 114.3)
		)
		(stroke
			(width 0)
			(type default)
		)
	)
	(wire
		(pts
			(xy 210.82 86.36) (xy 228.6 86.36)
		)
		(stroke
			(width 0)
			(type default)
		)
	)
	(bus
		(pts
			(xy 299.72 100.33) (xy 300.99 99.06)
		)
		(stroke
			(width 0)
			(type default)
		)
	)
	(wire
		(pts
			(xy 210.82 81.28) (xy 228.6 81.28)
		)
		(stroke
			(width 0)
			(type default)
		)
	)
	(wire
		(pts
			(xy 139.7 119.38) (xy 154.94 119.38)
		)
		(stroke
			(width 0)
			(type default)
		)
	)
	(bus
		(pts
			(xy 229.87 72.39) (xy 229.87 69.85)
		)
		(stroke
			(width 0)
			(type default)
		)
	)
	(bus
		(pts
			(xy 229.87 46.99) (xy 229.87 41.91)
		)
		(stroke
			(width 0)
			(type default)
		)
	)
	(bus
		(pts
			(xy 156.21 102.87) (xy 156.21 107.95)
		)
		(stroke
			(width 0)
			(type default)
		)
	)
	(wire
		(pts
			(xy 210.82 40.64) (xy 228.6 40.64)
		)
		(stroke
			(width 0)
			(type default)
		)
	)
	(wire
		(pts
			(xy 372.11 93.98) (xy 355.6 93.98)
		)
		(stroke
			(width 0)
			(type default)
		)
	)
	(wire
		(pts
			(xy 355.6 83.82) (xy 378.46 83.82)
		)
		(stroke
			(width 0)
			(type default)
		)
	)
	(wire
		(pts
			(xy 210.82 127) (xy 228.6 127)
		)
		(stroke
			(width 0)
			(type default)
		)
	)
	(bus
		(pts
			(xy 220.98 177.8) (xy 222.25 177.8)
		)
		(stroke
			(width 0)
			(type default)
		)
	)
	(bus
		(pts
			(xy 229.87 87.63) (xy 229.87 85.09)
		)
		(stroke
			(width 0)
			(type default)
		)
	)
	(bus
		(pts
			(xy 229.87 29.21) (xy 229.87 31.75)
		)
		(stroke
			(width 0)
			(type default)
		)
	)
	(wire
		(pts
			(xy 246.38 259.08) (xy 247.65 259.08)
		)
		(stroke
			(width 0)
			(type default)
		)
	)
	(bus
		(pts
			(xy 226.06 204.47) (xy 226.06 207.01)
		)
		(stroke
			(width 0)
			(type default)
		)
	)
	(bus
		(pts
			(xy 152.4 214.63) (xy 152.4 209.55)
		)
		(stroke
			(width 0)
			(type default)
		)
	)
	(bus
		(pts
			(xy 156.21 107.95) (xy 156.21 110.49)
		)
		(stroke
			(width 0)
			(type default)
		)
	)
	(bus
		(pts
			(xy 292.1 62.23) (xy 292.1 64.77)
		)
		(stroke
			(width 0)
			(type default)
		)
	)
	(wire
		(pts
			(xy 210.82 160.02) (xy 219.71 160.02)
		)
		(stroke
			(width 0)
			(type default)
		)
	)
	(wire
		(pts
			(xy 298.45 119.38) (xy 281.94 119.38)
		)
		(stroke
			(width 0)
			(type default)
		)
	)
	(bus
		(pts
			(xy 292.1 76.2) (xy 292.1 77.47)
		)
		(stroke
			(width 0)
			(type default)
		)
	)
	(wire
		(pts
			(xy 139.7 116.84) (xy 154.94 116.84)
		)
		(stroke
			(width 0)
			(type default)
		)
	)
	(wire
		(pts
			(xy 210.82 71.12) (xy 228.6 71.12)
		)
		(stroke
			(width 0)
			(type default)
		)
	)
	(wire
		(pts
			(xy 139.7 109.22) (xy 154.94 109.22)
		)
		(stroke
			(width 0)
			(type default)
		)
	)
	(bus
		(pts
			(xy 152.4 229.87) (xy 152.4 224.79)
		)
		(stroke
			(width 0)
			(type default)
		)
	)
	(bus
		(pts
			(xy 229.87 80.01) (xy 229.87 77.47)
		)
		(stroke
			(width 0)
			(type default)
		)
	)
	(wire
		(pts
			(xy 281.94 63.5) (xy 290.83 63.5)
		)
		(stroke
			(width 0)
			(type default)
		)
	)
	(bus
		(pts
			(xy 156.21 125.73) (xy 156.21 130.81)
		)
		(stroke
			(width 0)
			(type default)
		)
	)
	(wire
		(pts
			(xy 210.82 116.84) (xy 228.6 116.84)
		)
		(stroke
			(width 0)
			(type default)
		)
	)
	(bus
		(pts
			(xy 303.53 119.38) (xy 300.99 119.38)
		)
		(stroke
			(width 0)
			(type default)
		)
	)
	(wire
		(pts
			(xy 210.82 33.02) (xy 228.6 33.02)
		)
		(stroke
			(width 0)
			(type default)
		)
	)
	(bus
		(pts
			(xy 226.06 204.47) (xy 226.06 203.2)
		)
		(stroke
			(width 0)
			(type default)
		)
	)
	(wire
		(pts
			(xy 298.45 182.88) (xy 281.94 182.88)
		)
		(stroke
			(width 0)
			(type default)
		)
	)
	(wire
		(pts
			(xy 210.82 93.98) (xy 228.6 93.98)
		)
		(stroke
			(width 0)
			(type default)
		)
	)
	(wire
		(pts
			(xy 298.45 101.6) (xy 281.94 101.6)
		)
		(stroke
			(width 0)
			(type default)
		)
	)
	(wire
		(pts
			(xy 281.94 73.66) (xy 290.83 73.66)
		)
		(stroke
			(width 0)
			(type default)
		)
	)
	(bus
		(pts
			(xy 87.63 247.65) (xy 87.63 245.11)
		)
		(stroke
			(width 0)
			(type default)
		)
	)
	(wire
		(pts
			(xy 139.7 139.7) (xy 154.94 139.7)
		)
		(stroke
			(width 0)
			(type default)
		)
	)
	(wire
		(pts
			(xy 210.82 96.52) (xy 228.6 96.52)
		)
		(stroke
			(width 0)
			(type default)
		)
	)
	(bus
		(pts
			(xy 229.87 62.23) (xy 229.87 59.69)
		)
		(stroke
			(width 0)
			(type default)
		)
	)
	(bus
		(pts
			(xy 152.4 232.41) (xy 152.4 229.87)
		)
		(stroke
			(width 0)
			(type default)
		)
	)
	(wire
		(pts
			(xy 139.7 101.6) (xy 154.94 101.6)
		)
		(stroke
			(width 0)
			(type default)
		)
	)
	(wire
		(pts
			(xy 139.7 215.9) (xy 151.13 215.9)
		)
		(stroke
			(width 0)
			(type default)
		)
	)
	(bus
		(pts
			(xy 156.21 133.35) (xy 156.21 138.43)
		)
		(stroke
			(width 0)
			(type default)
		)
	)
	(bus
		(pts
			(xy 299.72 100.33) (xy 299.72 102.87)
		)
		(stroke
			(width 0)
			(type default)
		)
	)
	(bus
		(pts
			(xy 229.87 31.75) (xy 229.87 34.29)
		)
		(stroke
			(width 0)
			(type default)
		)
	)
	(bus
		(pts
			(xy 297.18 60.96) (xy 292.1 60.96)
		)
		(stroke
			(width 0)
			(type default)
		)
	)
	(bus
		(pts
			(xy 220.98 162.56) (xy 222.25 162.56)
		)
		(stroke
			(width 0)
			(type default)
		)
	)
	(bus
		(pts
			(xy 229.87 107.95) (xy 229.87 102.87)
		)
		(stroke
			(width 0)
			(type default)
		)
	)
	(bus
		(pts
			(xy 156.21 54.61) (xy 156.21 57.15)
		)
		(stroke
			(width 0)
			(type default)
		)
	)
	(bus
		(pts
			(xy 229.87 59.69) (xy 232.41 59.69)
		)
		(stroke
			(width 0)
			(type default)
		)
	)
	(bus
		(pts
			(xy 292.1 72.39) (xy 292.1 69.85)
		)
		(stroke
			(width 0)
			(type default)
		)
	)
	(bus
		(pts
			(xy 220.98 179.07) (xy 220.98 181.61)
		)
		(stroke
			(width 0)
			(type default)
		)
	)
	(wire
		(pts
			(xy 303.53 127) (xy 281.94 127)
		)
		(stroke
			(width 0)
			(type default)
		)
	)
	(bus
		(pts
			(xy 156.21 39.37) (xy 156.21 41.91)
		)
		(stroke
			(width 0)
			(type default)
		)
	)
	(bus
		(pts
			(xy 229.87 120.65) (xy 231.14 120.65)
		)
		(stroke
			(width 0)
			(type default)
		)
	)
	(wire
		(pts
			(xy 210.82 109.22) (xy 228.6 109.22)
		)
		(stroke
			(width 0)
			(type default)
		)
	)
	(wire
		(pts
			(xy 139.7 147.32) (xy 154.94 147.32)
		)
		(stroke
			(width 0)
			(type default)
		)
	)
	(bus
		(pts
			(xy 156.21 138.43) (xy 156.21 140.97)
		)
		(stroke
			(width 0)
			(type default)
		)
	)
	(wire
		(pts
			(xy 139.7 35.56) (xy 154.94 35.56)
		)
		(stroke
			(width 0)
			(type default)
		)
	)
	(bus
		(pts
			(xy 299.72 181.61) (xy 300.99 180.34)
		)
		(stroke
			(width 0)
			(type default)
		)
	)
	(bus
		(pts
			(xy 156.21 30.48) (xy 156.21 31.75)
		)
		(stroke
			(width 0)
			(type default)
		)
	)
	(bus
		(pts
			(xy 156.21 30.48) (xy 160.02 30.48)
		)
		(stroke
			(width 0)
			(type default)
		)
	)
	(bus
		(pts
			(xy 156.21 31.75) (xy 156.21 34.29)
		)
		(stroke
			(width 0)
			(type default)
		)
	)
	(wire
		(pts
			(xy 139.7 231.14) (xy 151.13 231.14)
		)
		(stroke
			(width 0)
			(type default)
		)
	)
	(bus
		(pts
			(xy 152.4 207.01) (xy 156.21 207.01)
		)
		(stroke
			(width 0)
			(type default)
		)
	)
	(wire
		(pts
			(xy 68.58 248.92) (xy 86.36 248.92)
		)
		(stroke
			(width 0)
			(type default)
		)
	)
	(bus
		(pts
			(xy 156.21 146.05) (xy 156.21 148.59)
		)
		(stroke
			(width 0)
			(type default)
		)
	)
	(wire
		(pts
			(xy 281.94 66.04) (xy 290.83 66.04)
		)
		(stroke
			(width 0)
			(type default)
		)
	)
	(wire
		(pts
			(xy 246.38 246.38) (xy 246.38 252.73)
		)
		(stroke
			(width 0)
			(type default)
		)
	)
	(wire
		(pts
			(xy 139.7 142.24) (xy 154.94 142.24)
		)
		(stroke
			(width 0)
			(type default)
		)
	)
	(wire
		(pts
			(xy 210.82 58.42) (xy 228.6 58.42)
		)
		(stroke
			(width 0)
			(type default)
		)
	)
	(wire
		(pts
			(xy 139.7 111.76) (xy 154.94 111.76)
		)
		(stroke
			(width 0)
			(type default)
		)
	)
	(wire
		(pts
			(xy 139.7 241.3) (xy 151.13 241.3)
		)
		(stroke
			(width 0)
			(type default)
		)
	)
	(bus
		(pts
			(xy 229.87 29.21) (xy 232.41 29.21)
		)
		(stroke
			(width 0)
			(type default)
		)
	)
	(bus
		(pts
			(xy 297.18 76.2) (xy 292.1 76.2)
		)
		(stroke
			(width 0)
			(type default)
		)
	)
	(bus
		(pts
			(xy 226.06 207.01) (xy 226.06 212.09)
		)
		(stroke
			(width 0)
			(type default)
		)
	)
	(wire
		(pts
			(xy 148.59 254) (xy 139.7 254)
		)
		(stroke
			(width 0)
			(type default)
		)
	)
	(bus
		(pts
			(xy 373.38 77.47) (xy 373.38 85.09)
		)
		(stroke
			(width 0)
			(type default)
		)
	)
	(wire
		(pts
			(xy 139.7 149.86) (xy 154.94 149.86)
		)
		(stroke
			(width 0)
			(type default)
		)
	)
	(bus
		(pts
			(xy 87.63 270.51) (xy 87.63 267.97)
		)
		(stroke
			(width 0)
			(type default)
		)
	)
	(wire
		(pts
			(xy 139.7 81.28) (xy 154.94 81.28)
		)
		(stroke
			(width 0)
			(type default)
		)
	)
	(wire
		(pts
			(xy 210.82 165.1) (xy 219.71 165.1)
		)
		(stroke
			(width 0)
			(type default)
		)
	)
	(wire
		(pts
			(xy 210.82 111.76) (xy 228.6 111.76)
		)
		(stroke
			(width 0)
			(type default)
		)
	)
	(bus
		(pts
			(xy 220.98 154.94) (xy 222.25 154.94)
		)
		(stroke
			(width 0)
			(type default)
		)
	)
	(wire
		(pts
			(xy 372.11 88.9) (xy 355.6 88.9)
		)
		(stroke
			(width 0)
			(type default)
		)
	)
	(wire
		(pts
			(xy 210.82 157.48) (xy 219.71 157.48)
		)
		(stroke
			(width 0)
			(type default)
		)
	)
	(bus
		(pts
			(xy 292.1 87.63) (xy 292.1 85.09)
		)
		(stroke
			(width 0)
			(type default)
		)
	)
	(wire
		(pts
			(xy 210.82 180.34) (xy 219.71 180.34)
		)
		(stroke
			(width 0)
			(type default)
		)
	)
	(bus
		(pts
			(xy 156.21 41.91) (xy 156.21 46.99)
		)
		(stroke
			(width 0)
			(type default)
		)
	)
	(wire
		(pts
			(xy 369.57 81.28) (xy 369.57 95.25)
		)
		(stroke
			(width 0)
			(type default)
		)
	)
	(wire
		(pts
			(xy 372.11 86.36) (xy 355.6 86.36)
		)
		(stroke
			(width 0)
			(type default)
		)
	)
	(wire
		(pts
			(xy 210.82 167.64) (xy 219.71 167.64)
		)
		(stroke
			(width 0)
			(type default)
		)
	)
	(bus
		(pts
			(xy 229.87 125.73) (xy 229.87 123.19)
		)
		(stroke
			(width 0)
			(type default)
		)
	)
	(wire
		(pts
			(xy 210.82 73.66) (xy 228.6 73.66)
		)
		(stroke
			(width 0)
			(type default)
		)
	)
	(wire
		(pts
			(xy 139.7 93.98) (xy 154.94 93.98)
		)
		(stroke
			(width 0)
			(type default)
		)
	)
	(wire
		(pts
			(xy 210.82 193.04) (xy 220.98 193.04)
		)
		(stroke
			(width 0)
			(type default)
		)
	)
	(bus
		(pts
			(xy 156.21 140.97) (xy 156.21 146.05)
		)
		(stroke
			(width 0)
			(type default)
		)
	)
	(wire
		(pts
			(xy 139.7 127) (xy 154.94 127)
		)
		(stroke
			(width 0)
			(type default)
		)
	)
	(bus
		(pts
			(xy 226.06 218.44) (xy 227.33 218.44)
		)
		(stroke
			(width 0)
			(type default)
		)
	)
	(bus
		(pts
			(xy 156.21 100.33) (xy 156.21 102.87)
		)
		(stroke
			(width 0)
			(type default)
		)
	)
	(bus
		(pts
			(xy 229.87 64.77) (xy 229.87 62.23)
		)
		(stroke
			(width 0)
			(type default)
		)
	)
	(bus
		(pts
			(xy 373.38 90.17) (xy 373.38 92.71)
		)
		(stroke
			(width 0)
			(type default)
		)
	)
	(wire
		(pts
			(xy 210.82 220.98) (xy 224.79 220.98)
		)
		(stroke
			(width 0)
			(type default)
		)
	)
	(wire
		(pts
			(xy 68.58 254) (xy 86.36 254)
		)
		(stroke
			(width 0)
			(type default)
		)
	)
	(bus
		(pts
			(xy 220.98 170.18) (xy 222.25 170.18)
		)
		(stroke
			(width 0)
			(type default)
		)
	)
	(wire
		(pts
			(xy 213.36 187.96) (xy 210.82 187.96)
		)
		(stroke
			(width 0)
			(type default)
		)
	)
	(bus
		(pts
			(xy 229.87 123.19) (xy 229.87 120.65)
		)
		(stroke
			(width 0)
			(type default)
		)
	)
	(bus
		(pts
			(xy 156.21 80.01) (xy 156.21 85.09)
		)
		(stroke
			(width 0)
			(type default)
		)
	)
	(wire
		(pts
			(xy 210.82 119.38) (xy 228.6 119.38)
		)
		(stroke
			(width 0)
			(type default)
		)
	)
	(bus
		(pts
			(xy 303.53 99.06) (xy 300.99 99.06)
		)
		(stroke
			(width 0)
			(type default)
		)
	)
	(wire
		(pts
			(xy 210.82 205.74) (xy 224.79 205.74)
		)
		(stroke
			(width 0)
			(type default)
		)
	)
	(bus
		(pts
			(xy 378.46 73.66) (xy 374.65 73.66)
		)
		(stroke
			(width 0)
			(type default)
		)
	)
	(bus
		(pts
			(xy 156.21 95.25) (xy 156.21 100.33)
		)
		(stroke
			(width 0)
			(type default)
		)
	)
	(wire
		(pts
			(xy 139.7 58.42) (xy 154.94 58.42)
		)
		(stroke
			(width 0)
			(type default)
		)
	)
	(bus
		(pts
			(xy 229.87 100.33) (xy 229.87 95.25)
		)
		(stroke
			(width 0)
			(type default)
		)
	)
	(bus
		(pts
			(xy 156.21 49.53) (xy 156.21 54.61)
		)
		(stroke
			(width 0)
			(type default)
		)
	)
	(bus
		(pts
			(xy 299.72 181.61) (xy 299.72 184.15)
		)
		(stroke
			(width 0)
			(type default)
		)
	)
	(wire
		(pts
			(xy 139.7 134.62) (xy 154.94 134.62)
		)
		(stroke
			(width 0)
			(type default)
		)
	)
	(wire
		(pts
			(xy 303.53 93.98) (xy 281.94 93.98)
		)
		(stroke
			(width 0)
			(type default)
		)
	)
	(bus
		(pts
			(xy 152.4 217.17) (xy 152.4 214.63)
		)
		(stroke
			(width 0)
			(type default)
		)
	)
	(wire
		(pts
			(xy 210.82 228.6) (xy 224.79 228.6)
		)
		(stroke
			(width 0)
			(type default)
		)
	)
	(bus
		(pts
			(xy 156.21 85.09) (xy 156.21 87.63)
		)
		(stroke
			(width 0)
			(type default)
		)
	)
	(bus
		(pts
			(xy 229.87 102.87) (xy 229.87 100.33)
		)
		(stroke
			(width 0)
			(type default)
		)
	)
	(wire
		(pts
			(xy 355.6 76.2) (xy 372.11 76.2)
		)
		(stroke
			(width 0)
			(type default)
		)
	)
	(wire
		(pts
			(xy 298.45 116.84) (xy 281.94 116.84)
		)
		(stroke
			(width 0)
			(type default)
		)
	)
	(bus
		(pts
			(xy 156.21 62.23) (xy 156.21 64.77)
		)
		(stroke
			(width 0)
			(type default)
		)
	)
	(bus
		(pts
			(xy 229.87 115.57) (xy 229.87 110.49)
		)
		(stroke
			(width 0)
			(type default)
		)
	)
	(wire
		(pts
			(xy 139.7 33.02) (xy 154.94 33.02)
		)
		(stroke
			(width 0)
			(type default)
		)
	)
	(bus
		(pts
			(xy 87.63 212.09) (xy 87.63 245.11)
		)
		(stroke
			(width 0)
			(type default)
		)
	)
	(bus
		(pts
			(xy 156.21 64.77) (xy 156.21 69.85)
		)
		(stroke
			(width 0)
			(type default)
		)
	)
	(wire
		(pts
			(xy 210.82 78.74) (xy 228.6 78.74)
		)
		(stroke
			(width 0)
			(type default)
		)
	)
	(wire
		(pts
			(xy 298.45 106.68) (xy 281.94 106.68)
		)
		(stroke
			(width 0)
			(type default)
		)
	)
	(bus
		(pts
			(xy 156.21 72.39) (xy 156.21 77.47)
		)
		(stroke
			(width 0)
			(type default)
		)
	)
	(bus
		(pts
			(xy 220.98 166.37) (xy 220.98 163.83)
		)
		(stroke
			(width 0)
			(type default)
		)
	)
	(bus
		(pts
			(xy 226.06 203.2) (xy 227.33 203.2)
		)
		(stroke
			(width 0)
			(type default)
		)
	)
	(wire
		(pts
			(xy 246.38 265.43) (xy 246.38 271.78)
		)
		(stroke
			(width 0)
			(type default)
		)
	)
	(bus
		(pts
			(xy 299.72 120.65) (xy 299.72 123.19)
		)
		(stroke
			(width 0)
			(type default)
		)
	)
	(bus
		(pts
			(xy 292.1 60.96) (xy 292.1 62.23)
		)
		(stroke
			(width 0)
			(type default)
		)
	)
	(bus
		(pts
			(xy 152.4 222.25) (xy 152.4 217.17)
		)
		(stroke
			(width 0)
			(type default)
		)
	)
	(bus
		(pts
			(xy 229.87 95.25) (xy 229.87 92.71)
		)
		(stroke
			(width 0)
			(type default)
		)
	)
	(wire
		(pts
			(xy 210.82 124.46) (xy 228.6 124.46)
		)
		(stroke
			(width 0)
			(type default)
		)
	)
	(bus
		(pts
			(xy 229.87 110.49) (xy 229.87 107.95)
		)
		(stroke
			(width 0)
			(type default)
		)
	)
	(wire
		(pts
			(xy 298.45 124.46) (xy 281.94 124.46)
		)
		(stroke
			(width 0)
			(type default)
		)
	)
	(bus
		(pts
			(xy 229.87 85.09) (xy 229.87 80.01)
		)
		(stroke
			(width 0)
			(type default)
		)
	)
	(wire
		(pts
			(xy 148.59 251.46) (xy 139.7 251.46)
		)
		(stroke
			(width 0)
			(type default)
		)
	)
	(wire
		(pts
			(xy 246.38 246.38) (xy 247.65 246.38)
		)
		(stroke
			(width 0)
			(type default)
		)
	)
	(bus
		(pts
			(xy 156.21 91.44) (xy 160.02 91.44)
		)
		(stroke
			(width 0)
			(type default)
		)
	)
	(bus
		(pts
			(xy 226.06 212.09) (xy 226.06 214.63)
		)
		(stroke
			(width 0)
			(type default)
		)
	)
	(bus
		(pts
			(xy 87.63 267.97) (xy 87.63 262.89)
		)
		(stroke
			(width 0)
			(type default)
		)
	)
	(bus
		(pts
			(xy 292.1 69.85) (xy 292.1 64.77)
		)
		(stroke
			(width 0)
			(type default)
		)
	)
	(bus
		(pts
			(xy 156.21 110.49) (xy 156.21 115.57)
		)
		(stroke
			(width 0)
			(type default)
		)
	)
	(wire
		(pts
			(xy 355.6 78.74) (xy 372.11 78.74)
		)
		(stroke
			(width 0)
			(type default)
		)
	)
	(bus
		(pts
			(xy 229.87 118.11) (xy 229.87 115.57)
		)
		(stroke
			(width 0)
			(type default)
		)
	)
	(wire
		(pts
			(xy 281.94 81.28) (xy 290.83 81.28)
		)
		(stroke
			(width 0)
			(type default)
		)
	)
	(wire
		(pts
			(xy 210.82 101.6) (xy 228.6 101.6)
		)
		(stroke
			(width 0)
			(type default)
		)
	)
	(wire
		(pts
			(xy 303.53 111.76) (xy 281.94 111.76)
		)
		(stroke
			(width 0)
			(type default)
		)
	)
	(wire
		(pts
			(xy 298.45 104.14) (xy 281.94 104.14)
		)
		(stroke
			(width 0)
			(type default)
		)
	)
	(wire
		(pts
			(xy 210.82 55.88) (xy 228.6 55.88)
		)
		(stroke
			(width 0)
			(type default)
		)
	)
	(wire
		(pts
			(xy 68.58 246.38) (xy 86.36 246.38)
		)
		(stroke
			(width 0)
			(type default)
		)
	)
	(bus
		(pts
			(xy 229.87 39.37) (xy 229.87 34.29)
		)
		(stroke
			(width 0)
			(type default)
		)
	)
	(bus
		(pts
			(xy 373.38 74.93) (xy 374.65 73.66)
		)
		(stroke
			(width 0)
			(type default)
		)
	)
	(bus
		(pts
			(xy 156.21 69.85) (xy 156.21 72.39)
		)
		(stroke
			(width 0)
			(type default)
		)
	)
	(wire
		(pts
			(xy 68.58 264.16) (xy 86.36 264.16)
		)
		(stroke
			(width 0)
			(type default)
		)
	)
	(wire
		(pts
			(xy 210.82 223.52) (xy 224.79 223.52)
		)
		(stroke
			(width 0)
			(type default)
		)
	)
	(bus
		(pts
			(xy 220.98 163.83) (xy 220.98 162.56)
		)
		(stroke
			(width 0)
			(type default)
		)
	)
	(wire
		(pts
			(xy 281.94 86.36) (xy 290.83 86.36)
		)
		(stroke
			(width 0)
			(type default)
		)
	)
	(wire
		(pts
			(xy 139.7 86.36) (xy 154.94 86.36)
		)
		(stroke
			(width 0)
			(type default)
		)
	)
	(bus
		(pts
			(xy 156.21 46.99) (xy 156.21 49.53)
		)
		(stroke
			(width 0)
			(type default)
		)
	)
	(bus
		(pts
			(xy 373.38 87.63) (xy 373.38 90.17)
		)
		(stroke
			(width 0)
			(type default)
		)
	)
	(bus
		(pts
			(xy 373.38 85.09) (xy 373.38 87.63)
		)
		(stroke
			(width 0)
			(type default)
		)
	)
	(bus
		(pts
			(xy 299.72 105.41) (xy 299.72 107.95)
		)
		(stroke
			(width 0)
			(type default)
		)
	)
	(bus
		(pts
			(xy 152.4 224.79) (xy 152.4 222.25)
		)
		(stroke
			(width 0)
			(type default)
		)
	)
	(bus
		(pts
			(xy 152.4 237.49) (xy 152.4 232.41)
		)
		(stroke
			(width 0)
			(type default)
		)
	)
	(bus
		(pts
			(xy 152.4 240.03) (xy 152.4 237.49)
		)
		(stroke
			(width 0)
			(type default)
		)
	)
	(bus
		(pts
			(xy 299.72 105.41) (xy 300.99 104.14)
		)
		(stroke
			(width 0)
			(type default)
		)
	)
	(bus
		(pts
			(xy 156.21 123.19) (xy 156.21 125.73)
		)
		(stroke
			(width 0)
			(type default)
		)
	)
	(wire
		(pts
			(xy 281.94 71.12) (xy 290.83 71.12)
		)
		(stroke
			(width 0)
			(type default)
		)
	)
	(wire
		(pts
			(xy 355.6 81.28) (xy 369.57 81.28)
		)
		(stroke
			(width 0)
			(type default)
		)
	)
	(wire
		(pts
			(xy 298.45 121.92) (xy 281.94 121.92)
		)
		(stroke
			(width 0)
			(type default)
		)
	)
	(wire
		(pts
			(xy 210.82 175.26) (xy 219.71 175.26)
		)
		(stroke
			(width 0)
			(type default)
		)
	)
	(bus
		(pts
			(xy 87.63 212.09) (xy 90.17 212.09)
		)
		(stroke
			(width 0)
			(type default)
		)
	)
	(bus
		(pts
			(xy 156.21 118.11) (xy 156.21 123.19)
		)
		(stroke
			(width 0)
			(type default)
		)
	)
	(bus
		(pts
			(xy 152.4 209.55) (xy 152.4 207.01)
		)
		(stroke
			(width 0)
			(type default)
		)
	)
	(wire
		(pts
			(xy 210.82 43.18) (xy 228.6 43.18)
		)
		(stroke
			(width 0)
			(type default)
		)
	)
	(bus
		(pts
			(xy 292.1 77.47) (xy 292.1 80.01)
		)
		(stroke
			(width 0)
			(type default)
		)
	)
	(wire
		(pts
			(xy 139.7 104.14) (xy 154.94 104.14)
		)
		(stroke
			(width 0)
			(type default)
		)
	)
	(bus
		(pts
			(xy 220.98 158.75) (xy 220.98 156.21)
		)
		(stroke
			(width 0)
			(type default)
		)
	)
	(label "PCIe_{B1x4}.TX3-"
		(at 210.82 66.04 0)
		(effects
			(font
				(size 1.27 1.27)
			)
			(justify left bottom)
		)
	)
	(label "SDIO.DAT2"
		(at 358.14 91.44 0)
		(effects
			(font
				(size 1.27 1.27)
			)
			(justify left bottom)
		)
	)
	(label "I2C_{SFP1}.SCL"
		(at 298.45 119.38 180)
		(effects
			(font
				(size 1.27 1.27)
			)
			(justify right bottom)
		)
	)
	(label "PCIe_{B3x2}.RX0+"
		(at 68.58 269.24 0)
		(effects
			(font
				(size 1.27 1.27)
			)
			(justify left bottom)
		)
	)
	(label "PCIe_{B3x2}.RX1-"
		(at 68.58 256.54 0)
		(effects
			(font
				(size 1.27 1.27)
			)
			(justify left bottom)
		)
	)
	(label "PCIe_{B1x2}.TX1-"
		(at 210.82 35.56 0)
		(effects
			(font
				(size 1.27 1.27)
			)
			(justify left bottom)
		)
	)
	(label "USB1.D+"
		(at 210.82 172.72 0)
		(effects
			(font
				(size 1.27 1.27)
			)
			(justify left bottom)
		)
	)
	(label "PCIe_{B1x4}.TX3+"
		(at 210.82 63.5 0)
		(effects
			(font
				(size 1.27 1.27)
			)
			(justify left bottom)
		)
	)
	(label "PCIe_{B3x2}.TX1+"
		(at 68.58 246.38 0)
		(effects
			(font
				(size 1.27 1.27)
			)
			(justify left bottom)
		)
	)
	(label "PCIe_{B1x4}.RX3+"
		(at 210.82 71.12 0)
		(effects
			(font
				(size 1.27 1.27)
			)
			(justify left bottom)
		)
	)
	(label "KR0.RX-"
		(at 290.83 88.9 180)
		(effects
			(font
				(size 1.27 1.27)
			)
			(justify right bottom)
		)
	)
	(label "PCIe_{B2Bx4}.TX2-"
		(at 139.7 50.8 0)
		(effects
			(font
				(size 1.27 1.27)
			)
			(justify left bottom)
		)
	)
	(label "PCIe_{B2Bx4}.TX0-"
		(at 139.7 81.28 0)
		(effects
			(font
				(size 1.27 1.27)
			)
			(justify left bottom)
		)
	)
	(label "SDIO.DAT3"
		(at 358.14 93.98 0)
		(effects
			(font
				(size 1.27 1.27)
			)
			(justify left bottom)
		)
	)
	(label "USB3.D-"
		(at 210.82 160.02 0)
		(effects
			(font
				(size 1.27 1.27)
			)
			(justify left bottom)
		)
	)
	(label "PCIe_{B1x4}.RX2+"
		(at 210.82 86.36 0)
		(effects
			(font
				(size 1.27 1.27)
			)
			(justify left bottom)
		)
	)
	(label "USBSS3.RX+"
		(at 210.82 213.36 0)
		(effects
			(font
				(size 1.27 1.27)
			)
			(justify left bottom)
		)
	)
	(label "USB2.D-"
		(at 210.82 167.64 0)
		(effects
			(font
				(size 1.27 1.27)
			)
			(justify left bottom)
		)
	)
	(label "PCIe_{B2Ax4}.TX3+"
		(at 139.7 93.98 0)
		(effects
			(font
				(size 1.27 1.27)
			)
			(justify left bottom)
		)
	)
	(label "USB3.D+"
		(at 210.82 157.48 0)
		(effects
			(font
				(size 1.27 1.27)
			)
			(justify left bottom)
		)
	)
	(label "USBSS2.TX+"
		(at 210.82 220.98 0)
		(effects
			(font
				(size 1.27 1.27)
			)
			(justify left bottom)
		)
	)
	(label "PCIe_{B3x2}.TX0+"
		(at 68.58 261.62 0)
		(effects
			(font
				(size 1.27 1.27)
			)
			(justify left bottom)
		)
	)
	(label "PCIe_{B2Ax4}.RX3-"
		(at 139.7 104.14 0)
		(effects
			(font
				(size 1.27 1.27)
			)
			(justify left bottom)
		)
	)
	(label "GBE0.MDI2-"
		(at 139.7 226.06 0)
		(effects
			(font
				(size 1.27 1.27)
			)
			(justify left bottom)
		)
	)
	(label "USBSS2.RX+"
		(at 210.82 228.6 0)
		(effects
			(font
				(size 1.27 1.27)
			)
			(justify left bottom)
		)
	)
	(label "PCIe_{B1x2}.TX0-"
		(at 210.82 50.8 0)
		(effects
			(font
				(size 1.27 1.27)
			)
			(justify left bottom)
		)
	)
	(label "PCIe_{B2Ax4}.RX0+"
		(at 139.7 147.32 0)
		(effects
			(font
				(size 1.27 1.27)
			)
			(justify left bottom)
		)
	)
	(label "MDIO1.MDIO"
		(at 298.45 121.92 180)
		(effects
			(font
				(size 1.27 1.27)
			)
			(justify right bottom)
		)
	)
	(label "GBE0.MDI2+"
		(at 139.7 223.52 0)
		(effects
			(font
				(size 1.27 1.27)
			)
			(justify left bottom)
		)
	)
	(label "PCIe_{B2Ax4}.RX1-"
		(at 139.7 134.62 0)
		(effects
			(font
				(size 1.27 1.27)
			)
			(justify left bottom)
		)
	)
	(label "KR1.TX-"
		(at 290.83 66.04 180)
		(effects
			(font
				(size 1.27 1.27)
			)
			(justify right bottom)
		)
	)
	(label "GBE0.MDI1-"
		(at 139.7 233.68 0)
		(effects
			(font
				(size 1.27 1.27)
			)
			(justify left bottom)
		)
	)
	(label "SDIO.CMD"
		(at 358.14 78.74 0)
		(effects
			(font
				(size 1.27 1.27)
			)
			(justify left bottom)
		)
	)
	(label "SD_WP"
		(at 367.03 81.28 180)
		(effects
			(font
				(size 1.27 1.27)
			)
			(justify right bottom)
		)
	)
	(label "I2C_{SFP0}.SCL"
		(at 298.45 104.14 180)
		(effects
			(font
				(size 1.27 1.27)
			)
			(justify right bottom)
		)
	)
	(label "PCIe_{B1x4}.RX2-"
		(at 210.82 88.9 0)
		(effects
			(font
				(size 1.27 1.27)
			)
			(justify left bottom)
		)
	)
	(label "USB0.D+"
		(at 210.82 180.34 0)
		(effects
			(font
				(size 1.27 1.27)
			)
			(justify left bottom)
		)
	)
	(label "SDIO.CLK"
		(at 358.14 76.2 0)
		(effects
			(font
				(size 1.27 1.27)
			)
			(justify left bottom)
		)
	)
	(label "KR1.RX-"
		(at 290.83 73.66 180)
		(effects
			(font
				(size 1.27 1.27)
			)
			(justify right bottom)
		)
	)
	(label "GBE0.MDI3+"
		(at 139.7 215.9 0)
		(effects
			(font
				(size 1.27 1.27)
			)
			(justify left bottom)
		)
	)
	(label "PCIe_{B2Ax4}.RX2-"
		(at 139.7 119.38 0)
		(effects
			(font
				(size 1.27 1.27)
			)
			(justify left bottom)
		)
	)
	(label "PCIe_{B2Bx4}.RX3+"
		(at 139.7 40.64 0)
		(effects
			(font
				(size 1.27 1.27)
			)
			(justify left bottom)
		)
	)
	(label "PCIe_{B1x4}.TX1+"
		(at 210.82 93.98 0)
		(effects
			(font
				(size 1.27 1.27)
			)
			(justify left bottom)
		)
	)
	(label "PCIe_{B2Ax4}.TX0-"
		(at 139.7 142.24 0)
		(effects
			(font
				(size 1.27 1.27)
			)
			(justify left bottom)
		)
	)
	(label "PCIe_{B3x2}.RX0-"
		(at 68.58 271.78 0)
		(effects
			(font
				(size 1.27 1.27)
			)
			(justify left bottom)
		)
	)
	(label "GBE0.MDI3-"
		(at 139.7 218.44 0)
		(effects
			(font
				(size 1.27 1.27)
			)
			(justify left bottom)
		)
	)
	(label "PCIE_{REF}.CK-"
		(at 210.82 127 0)
		(effects
			(font
				(size 1.27 1.27)
			)
			(justify left bottom)
		)
	)
	(label "PCIe_{B1x4}.TX2+"
		(at 210.82 78.74 0)
		(effects
			(font
				(size 1.27 1.27)
			)
			(justify left bottom)
		)
	)
	(label "KR0.TX+"
		(at 290.83 78.74 180)
		(effects
			(font
				(size 1.27 1.27)
			)
			(justify right bottom)
		)
	)
	(label "GBE0.CTREF"
		(at 139.7 210.82 0)
		(effects
			(font
				(size 1.27 1.27)
			)
			(justify left bottom)
		)
	)
	(label "PCIE_{REF}.CK+"
		(at 210.82 124.46 0)
		(effects
			(font
				(size 1.27 1.27)
			)
			(justify left bottom)
		)
	)
	(label "PCIe_{B2Ax4}.RX0-"
		(at 139.7 149.86 0)
		(effects
			(font
				(size 1.27 1.27)
			)
			(justify left bottom)
		)
	)
	(label "PCIe_{B2Bx4}.RX0-"
		(at 139.7 88.9 0)
		(effects
			(font
				(size 1.27 1.27)
			)
			(justify left bottom)
		)
	)
	(label "MDIO0.MDIO"
		(at 298.45 106.68 180)
		(effects
			(font
				(size 1.27 1.27)
			)
			(justify right bottom)
		)
	)
	(label "PCIe_{B1x4}.RX1+"
		(at 210.82 101.6 0)
		(effects
			(font
				(size 1.27 1.27)
			)
			(justify left bottom)
		)
	)
	(label "PCIe_{B2Bx4}.TX1+"
		(at 139.7 63.5 0)
		(effects
			(font
				(size 1.27 1.27)
			)
			(justify left bottom)
		)
	)
	(label "PCIe_{B1x4}.TX2-"
		(at 210.82 81.28 0)
		(effects
			(font
				(size 1.27 1.27)
			)
			(justify left bottom)
		)
	)
	(label "PCIe_{B2Ax4}.TX2+"
		(at 139.7 109.22 0)
		(effects
			(font
				(size 1.27 1.27)
			)
			(justify left bottom)
		)
	)
	(label "PCIe_{B2Bx4}.RX1+"
		(at 139.7 71.12 0)
		(effects
			(font
				(size 1.27 1.27)
			)
			(justify left bottom)
		)
	)
	(label "KR1.RX+"
		(at 290.83 71.12 180)
		(effects
			(font
				(size 1.27 1.27)
			)
			(justify right bottom)
		)
	)
	(label "USBSS3.RX-"
		(at 210.82 215.9 0)
		(effects
			(font
				(size 1.27 1.27)
			)
			(justify left bottom)
		)
	)
	(label "PCIe_{B2Ax4}.RX1+"
		(at 139.7 132.08 0)
		(effects
			(font
				(size 1.27 1.27)
			)
			(justify left bottom)
		)
	)
	(label "I2C_{SFP0}.SDA"
		(at 298.45 101.6 180)
		(effects
			(font
				(size 1.27 1.27)
			)
			(justify right bottom)
		)
	)
	(label "MDIO0.MDC"
		(at 298.45 109.22 180)
		(effects
			(font
				(size 1.27 1.27)
			)
			(justify right bottom)
		)
	)
	(label "GBE0.MDI0-"
		(at 139.7 241.3 0)
		(effects
			(font
				(size 1.27 1.27)
			)
			(justify left bottom)
		)
	)
	(label "PCIe_{B2Ax4}.TX2-"
		(at 139.7 111.76 0)
		(effects
			(font
				(size 1.27 1.27)
			)
			(justify left bottom)
		)
	)
	(label "PCIe_{B2Bx4}.RX2-"
		(at 139.7 58.42 0)
		(effects
			(font
				(size 1.27 1.27)
			)
			(justify left bottom)
		)
	)
	(label "PCIe_{B2Bx4}.RX3-"
		(at 139.7 43.18 0)
		(effects
			(font
				(size 1.27 1.27)
			)
			(justify left bottom)
		)
	)
	(label "KR0.TX-"
		(at 290.83 81.28 180)
		(effects
			(font
				(size 1.27 1.27)
			)
			(justify right bottom)
		)
	)
	(label "PCIe_{B1x2}.RX1-"
		(at 210.82 43.18 0)
		(effects
			(font
				(size 1.27 1.27)
			)
			(justify left bottom)
		)
	)
	(label "USBSS2.TX-"
		(at 210.82 223.52 0)
		(effects
			(font
				(size 1.27 1.27)
			)
			(justify left bottom)
		)
	)
	(label "I2C_{SFP1}.SDA"
		(at 298.45 116.84 180)
		(effects
			(font
				(size 1.27 1.27)
			)
			(justify right bottom)
		)
	)
	(label "PCIe_{B2Bx4}.RX1-"
		(at 139.7 73.66 0)
		(effects
			(font
				(size 1.27 1.27)
			)
			(justify left bottom)
		)
	)
	(label "GBE0.MDI1+"
		(at 139.7 231.14 0)
		(effects
			(font
				(size 1.27 1.27)
			)
			(justify left bottom)
		)
	)
	(label "PCIe_{B3x2}.TX1-"
		(at 68.58 248.92 0)
		(effects
			(font
				(size 1.27 1.27)
			)
			(justify left bottom)
		)
	)
	(label "USB0.D-"
		(at 210.82 182.88 0)
		(effects
			(font
				(size 1.27 1.27)
			)
			(justify left bottom)
		)
	)
	(label "PCIe_{B1x4}.TX0-"
		(at 210.82 111.76 0)
		(effects
			(font
				(size 1.27 1.27)
			)
			(justify left bottom)
		)
	)
	(label "USBSS2.RX-"
		(at 210.82 231.14 0)
		(effects
			(font
				(size 1.27 1.27)
			)
			(justify left bottom)
		)
	)
	(label "PCIe_{B2Bx4}.RX2+"
		(at 139.7 55.88 0)
		(effects
			(font
				(size 1.27 1.27)
			)
			(justify left bottom)
		)
	)
	(label "PCIe_{B1x2}.RX1+"
		(at 210.82 40.64 0)
		(effects
			(font
				(size 1.27 1.27)
			)
			(justify left bottom)
		)
	)
	(label "PCIe_{B2Bx4}.TX2+"
		(at 139.7 48.26 0)
		(effects
			(font
				(size 1.27 1.27)
			)
			(justify left bottom)
		)
	)
	(label "PCIe_{B2Bx4}.RX0+"
		(at 139.7 86.36 0)
		(effects
			(font
				(size 1.27 1.27)
			)
			(justify left bottom)
		)
	)
	(label "PCIe_{B2Ax4}.TX0+"
		(at 139.7 139.7 0)
		(effects
			(font
				(size 1.27 1.27)
			)
			(justify left bottom)
		)
	)
	(label "PCIe_{B3x2}.RX1+"
		(at 68.58 254 0)
		(effects
			(font
				(size 1.27 1.27)
			)
			(justify left bottom)
		)
	)
	(label "PCIe_{B2Ax4}.TX3-"
		(at 139.7 96.52 0)
		(effects
			(font
				(size 1.27 1.27)
			)
			(justify left bottom)
		)
	)
	(label "USB1.D-"
		(at 210.82 175.26 0)
		(effects
			(font
				(size 1.27 1.27)
			)
			(justify left bottom)
		)
	)
	(label "PCIe_{B1x4}.TX1-"
		(at 210.82 96.52 0)
		(effects
			(font
				(size 1.27 1.27)
			)
			(justify left bottom)
		)
	)
	(label "PCIe_{B1x2}.TX0+"
		(at 210.82 48.26 0)
		(effects
			(font
				(size 1.27 1.27)
			)
			(justify left bottom)
		)
	)
	(label "PCIe_{B1x4}.RX1-"
		(at 210.82 104.14 0)
		(effects
			(font
				(size 1.27 1.27)
			)
			(justify left bottom)
		)
	)
	(label "GBE0.MDI0+"
		(at 139.7 238.76 0)
		(effects
			(font
				(size 1.27 1.27)
			)
			(justify left bottom)
		)
	)
	(label "I2C_{10GLED}.SDA"
		(at 298.45 182.88 180)
		(effects
			(font
				(size 1.27 1.27)
			)
			(justify right bottom)
		)
	)
	(label "USB2.D+"
		(at 210.82 165.1 0)
		(effects
			(font
				(size 1.27 1.27)
			)
			(justify left bottom)
		)
	)
	(label "PCIe_{B1x4}.TX0+"
		(at 210.82 109.22 0)
		(effects
			(font
				(size 1.27 1.27)
			)
			(justify left bottom)
		)
	)
	(label "PCIe_{B2Bx4}.TX3-"
		(at 139.7 35.56 0)
		(effects
			(font
				(size 1.27 1.27)
			)
			(justify left bottom)
		)
	)
	(label "PCIe_{B2Bx4}.TX1-"
		(at 139.7 66.04 0)
		(effects
			(font
				(size 1.27 1.27)
			)
			(justify left bottom)
		)
	)
	(label "PCIe_{B2Ax4}.RX2+"
		(at 139.7 116.84 0)
		(effects
			(font
				(size 1.27 1.27)
			)
			(justify left bottom)
		)
	)
	(label "PCIe_{B3x2}.TX0-"
		(at 68.58 264.16 0)
		(effects
			(font
				(size 1.27 1.27)
			)
			(justify left bottom)
		)
	)
	(label "PCIe_{B2Ax4}.TX1-"
		(at 139.7 127 0)
		(effects
			(font
				(size 1.27 1.27)
			)
			(justify left bottom)
		)
	)
	(label "MDIO1.MDC"
		(at 298.45 124.46 180)
		(effects
			(font
				(size 1.27 1.27)
			)
			(justify right bottom)
		)
	)
	(label "PCIe_{B1x2}.RX0-"
		(at 210.82 58.42 0)
		(effects
			(font
				(size 1.27 1.27)
			)
			(justify left bottom)
		)
	)
	(label "PCIe_{B2Ax4}.RX3+"
		(at 139.7 101.6 0)
		(effects
			(font
				(size 1.27 1.27)
			)
			(justify left bottom)
		)
	)
	(label "I2C_{10GLED}.SCL"
		(at 298.45 185.42 180)
		(effects
			(font
				(size 1.27 1.27)
			)
			(justify right bottom)
		)
	)
	(label "PCIe_{B1x4}.RX0+"
		(at 210.82 116.84 0)
		(effects
			(font
				(size 1.27 1.27)
			)
			(justify left bottom)
		)
	)
	(label "USBSS3.TX+"
		(at 210.82 205.74 0)
		(effects
			(font
				(size 1.27 1.27)
			)
			(justify left bottom)
		)
	)
	(label "PCIe_{B2Bx4}.TX0+"
		(at 139.7 78.74 0)
		(effects
			(font
				(size 1.27 1.27)
			)
			(justify left bottom)
		)
	)
	(label "PCIe_{B2Bx4}.TX3+"
		(at 139.7 33.02 0)
		(effects
			(font
				(size 1.27 1.27)
			)
			(justify left bottom)
		)
	)
	(label "PCIe_{B1x2}.RX0+"
		(at 210.82 55.88 0)
		(effects
			(font
				(size 1.27 1.27)
			)
			(justify left bottom)
		)
	)
	(label "KR0.RX+"
		(at 290.83 86.36 180)
		(effects
			(font
				(size 1.27 1.27)
			)
			(justify right bottom)
		)
	)
	(label "SDIO.DAT1"
		(at 358.14 88.9 0)
		(effects
			(font
				(size 1.27 1.27)
			)
			(justify left bottom)
		)
	)
	(label "PCIe_{B2Ax4}.TX1+"
		(at 139.7 124.46 0)
		(effects
			(font
				(size 1.27 1.27)
			)
			(justify left bottom)
		)
	)
	(label "SDIO.DAT0"
		(at 358.14 86.36 0)
		(effects
			(font
				(size 1.27 1.27)
			)
			(justify left bottom)
		)
	)
	(label "USBSS3.TX-"
		(at 210.82 208.28 0)
		(effects
			(font
				(size 1.27 1.27)
			)
			(justify left bottom)
		)
	)
	(label "KR1.TX+"
		(at 290.83 63.5 180)
		(effects
			(font
				(size 1.27 1.27)
			)
			(justify right bottom)
		)
	)
	(label "PCIe_{B1x4}.RX3-"
		(at 210.82 73.66 0)
		(effects
			(font
				(size 1.27 1.27)
			)
			(justify left bottom)
		)
	)
	(label "PCIe_{B1x4}.RX0-"
		(at 210.82 119.38 0)
		(effects
			(font
				(size 1.27 1.27)
			)
			(justify left bottom)
		)
	)
	(label "PCIe_{B1x2}.TX1+"
		(at 210.82 33.02 0)
		(effects
			(font
				(size 1.27 1.27)
			)
			(justify left bottom)
		)
	)
	(hierarchical_label "USBSS3{USBSS}"
		(shape output)
		(at 227.33 203.2 0)
		(effects
			(font
				(size 1.27 1.27)
			)
			(justify left)
		)
	)
	(hierarchical_label "USB1{USB}"
		(shape output)
		(at 222.25 170.18 0)
		(effects
			(font
				(size 1.27 1.27)
			)
			(justify left)
		)
	)
	(hierarchical_label "10G_INT0"
		(shape input)
		(at 303.53 111.76 0)
		(effects
			(font
				(size 1.27 1.27)
			)
			(justify left)
		)
	)
	(hierarchical_label "SDIO{SDIO}"
		(shape output)
		(at 378.46 73.66 0)
		(effects
			(font
				(size 1.27 1.27)
			)
			(justify left)
		)
	)
	(hierarchical_label "~{USB_2_3_OC}"
		(shape input)
		(at 220.98 193.04 0)
		(effects
			(font
				(size 1.27 1.27)
			)
			(justify left)
		)
	)
	(hierarchical_label "10G_PHY_RST01"
		(shape output)
		(at 303.53 93.98 0)
		(effects
			(font
				(size 1.27 1.27)
			)
			(justify left)
		)
	)
	(hierarchical_label "10G_INT1"
		(shape input)
		(at 303.53 127 0)
		(effects
			(font
				(size 1.27 1.27)
			)
			(justify left)
		)
	)
	(hierarchical_label "~{GBE0_ACT}"
		(shape output)
		(at 148.59 254 0)
		(effects
			(font
				(size 1.27 1.27)
			)
			(justify left)
		)
	)
	(hierarchical_label "I2C_{SFP0}{I2C}"
		(shape output)
		(at 303.53 99.06 0)
		(effects
			(font
				(size 1.27 1.27)
			)
			(justify left)
		)
	)
	(hierarchical_label "~{GBE0_LINK_1000}"
		(shape output)
		(at 148.59 246.38 0)
		(effects
			(font
				(size 1.27 1.27)
			)
			(justify left)
		)
	)
	(hierarchical_label "MDIO0{MDIO}"
		(shape output)
		(at 303.53 104.14 0)
		(effects
			(font
				(size 1.27 1.27)
			)
			(justify left)
		)
	)
	(hierarchical_label "~{GBE0_LINK}"
		(shape output)
		(at 148.59 251.46 0)
		(effects
			(font
				(size 1.27 1.27)
			)
			(justify left)
		)
	)
	(hierarchical_label "MDIO1{MDIO}"
		(shape output)
		(at 303.53 119.38 0)
		(effects
			(font
				(size 1.27 1.27)
			)
			(justify left)
		)
	)
	(hierarchical_label "USB3{USB}"
		(shape output)
		(at 222.25 154.94 0)
		(effects
			(font
				(size 1.27 1.27)
			)
			(justify left)
		)
	)
	(hierarchical_label "I2C_{SFP1}{I2C}"
		(shape output)
		(at 303.53 114.3 0)
		(effects
			(font
				(size 1.27 1.27)
			)
			(justify left)
		)
	)
	(hierarchical_label "KR1{10GBaseKR}"
		(shape output)
		(at 297.18 60.96 0)
		(effects
			(font
				(size 1.27 1.27)
			)
			(justify left)
		)
	)
	(hierarchical_label "USBSS2{USBSS}"
		(shape output)
		(at 227.33 218.44 0)
		(effects
			(font
				(size 1.27 1.27)
			)
			(justify left)
		)
	)
	(hierarchical_label "PCIe_{B2Bx4}{PCIe}"
		(shape output)
		(at 160.02 30.48 0)
		(effects
			(font
				(size 1.27 1.27)
			)
			(justify left)
		)
	)
	(hierarchical_label "USB0{USB}"
		(shape output)
		(at 222.25 177.8 0)
		(effects
			(font
				(size 1.27 1.27)
			)
			(justify left)
		)
	)
	(hierarchical_label "PCIE_{REF}{PCIe_{REF}}"
		(shape output)
		(at 231.14 120.65 0)
		(effects
			(font
				(size 1.27 1.27)
			)
			(justify left)
		)
	)
	(hierarchical_label "PCIe_{B1x4}{PCIe}"
		(shape output)
		(at 232.41 59.69 0)
		(effects
			(font
				(size 1.27 1.27)
			)
			(justify left)
		)
	)
	(hierarchical_label "USB2{USB}"
		(shape output)
		(at 222.25 162.56 0)
		(effects
			(font
				(size 1.27 1.27)
			)
			(justify left)
		)
	)
	(hierarchical_label "PCIe_{B3x2}{PCIe}"
		(shape output)
		(at 90.17 212.09 0)
		(effects
			(font
				(size 1.27 1.27)
			)
			(justify left)
		)
	)
	(hierarchical_label "PCIe_{B2Ax4}{PCIe}"
		(shape output)
		(at 160.02 91.44 0)
		(effects
			(font
				(size 1.27 1.27)
			)
			(justify left)
		)
	)
	(hierarchical_label "KR0{10GBaseKR}"
		(shape output)
		(at 297.18 76.2 0)
		(effects
			(font
				(size 1.27 1.27)
			)
			(justify left)
		)
	)
	(hierarchical_label "GBE0{GbE}"
		(shape output)
		(at 156.21 207.01 0)
		(effects
			(font
				(size 1.27 1.27)
			)
			(justify left)
		)
	)
	(hierarchical_label "SD_CD"
		(shape input)
		(at 378.46 83.82 0)
		(effects
			(font
				(size 1.27 1.27)
			)
			(justify left)
		)
	)
	(hierarchical_label "I2C_{10GLED}{I2C}"
		(shape output)
		(at 303.53 180.34 0)
		(effects
			(font
				(size 1.27 1.27)
			)
			(justify left)
		)
	)
	(hierarchical_label "PCIe_{B1x2}{PCIe}"
		(shape output)
		(at 232.41 29.21 0)
		(effects
			(font
				(size 1.27 1.27)
			)
			(justify left)
		)
	)
	(symbol
		(lib_id "antmicroB2BConnectors:Plug_Bus_CE7_EPT_401-51501-51")
		(at 281.94 198.12 0)
		(unit 1)
		(exclude_from_sim no)
		(in_bom yes)
		(on_board yes)
		(dnp no)
		(fields_autoplaced yes)
		(property "Reference" "J12"
			(at 262.89 190.5 0)
			(effects
				(font
					(size 1.27 1.27)
					(thickness 0.15)
				)
			)
		)
		(property "Value" "Plug_Bus_CE7_EPT_401-51501-51"
			(at 335.28 210.82 0)
			(effects
				(font
					(size 1.27 1.27)
					(thickness 0.15)
				)
				(justify left bottom)
				(hide yes)
			)
		)
		(property "Footprint" "antmicro-footprints:EPT_401-51501-51"
			(at 335.28 213.36 0)
			(effects
				(font
					(size 1.27 1.27)
					(thickness 0.15)
				)
				(justify left bottom)
				(hide yes)
			)
		)
		(property "Datasheet" "https://www.farnell.com/datasheets/1905093.pdf"
			(at 335.28 215.9 0)
			(effects
				(font
					(size 1.27 1.27)
					(thickness 0.15)
				)
				(justify left bottom)
				(hide yes)
			)
		)
		(property "Description" ""
			(at 281.94 198.12 0)
			(effects
				(font
					(size 1.27 1.27)
				)
				(hide yes)
			)
		)
		(property "Author" "Antmicro"
			(at 335.28 218.44 0)
			(effects
				(font
					(size 1.27 1.27)
					(thickness 0.15)
				)
				(justify left bottom)
				(hide yes)
			)
		)
		(property "License" "Apache-2.0"
			(at 335.28 220.98 0)
			(effects
				(font
					(size 1.27 1.27)
					(thickness 0.15)
				)
				(justify left bottom)
				(hide yes)
			)
		)
		(property "Manufacturer" "ept"
			(at 335.28 203.2 0)
			(effects
				(font
					(size 1.27 1.27)
					(thickness 0.15)
				)
				(justify left bottom)
				(hide yes)
			)
		)
		(property "MPN" "401-51501-51"
			(at 262.89 193.04 0)
			(effects
				(font
					(size 1.27 1.27)
					(thickness 0.15)
				)
			)
		)
		(pin "C91"
		)
		(pin "C92"
		)
		(pin "A15"
		)
		(pin "A91"
		)
		(pin "C34"
		)
		(pin "C35"
		)
		(pin "D22"
		)
		(pin "D23"
		)
		(pin "D55"
		)
		(pin "D56"
		)
		(pin "C55"
		)
		(pin "C56"
		)
		(pin "C71"
		)
		(pin "C72"
		)
		(pin "C32"
		)
		(pin "C33"
		)
		(pin "B6"
		)
		(pin "B58"
		)
		(pin "B59"
		)
		(pin "D5"
		)
		(pin "D51"
		)
		(pin "A29"
		)
		(pin "D46"
		)
		(pin "D47"
		)
		(pin "C105"
		)
		(pin "C106"
		)
		(pin "A16"
		)
		(pin "B22"
		)
		(pin "B51"
		)
		(pin "B30"
		)
		(pin "A44"
		)
		(pin "C51"
		)
		(pin "C60"
		)
		(pin "A81"
		)
		(pin "A82"
		)
		(pin "D90"
		)
		(pin "D93"
		)
		(pin "B68"
		)
		(pin "B69"
		)
		(pin "C103"
		)
		(pin "C104"
		)
		(pin "C58"
		)
		(pin "C59"
		)
		(pin "D84"
		)
		(pin "D87"
		)
		(pin "A30"
		)
		(pin "B29"
		)
		(pin "A41"
		)
		(pin "C40"
		)
		(pin "C42"
		)
		(pin "D80"
		)
		(pin "D83"
		)
		(pin "B103"
		)
		(pin "A102"
		)
		(pin "C101"
		)
		(pin "C102"
		)
		(pin "D11"
		)
		(pin "D110"
		)
		(pin "B37"
		)
		(pin "B45"
		)
		(pin "C61"
		)
		(pin "C62"
		)
		(pin "A42"
		)
		(pin "B36"
		)
		(pin "B57"
		)
		(pin "D12"
		)
		(pin "D44"
		)
		(pin "D48"
		)
		(pin "B32"
		)
		(pin "B107"
		)
		(pin "B108"
		)
		(pin "B110"
		)
		(pin "B101"
		)
		(pin "C63"
		)
		(pin "C64"
		)
		(pin "B50"
		)
		(pin "A87"
		)
		(pin "A86"
		)
		(pin "B27"
		)
		(pin "D17"
		)
		(pin "D24"
		)
		(pin "D26"
		)
		(pin "D27"
		)
		(pin "A47"
		)
		(pin "C81"
		)
		(pin "C82"
		)
		(pin "C68"
		)
		(pin "C69"
		)
		(pin "A74"
		)
		(pin "A48"
		)
		(pin "A57"
		)
		(pin "A43"
		)
		(pin "A31"
		)
		(pin "D29"
		)
		(pin "D30"
		)
		(pin "C36"
		)
		(pin "C37"
		)
		(pin "C3"
		)
		(pin "A35"
		)
		(pin "A34"
		)
		(pin "B7"
		)
		(pin "B46"
		)
		(pin "B1"
		)
		(pin "B63"
		)
		(pin "A51"
		)
		(pin "A99"
		)
		(pin "B17"
		)
		(pin "C13"
		)
		(pin "C4"
		)
		(pin "B102"
		)
		(pin "C38"
		)
		(pin "C39"
		)
		(pin "B3"
		)
		(pin "A90"
		)
		(pin "A72"
		)
		(pin "B84"
		)
		(pin "D19"
		)
		(pin "D20"
		)
		(pin "D43"
		)
		(pin "D45"
		)
		(pin "A77"
		)
		(pin "A78"
		)
		(pin "B38"
		)
		(pin "B86"
		)
		(pin "D77"
		)
		(pin "D8"
		)
		(pin "A32"
		)
		(pin "B85"
		)
		(pin "D73"
		)
		(pin "D76"
		)
		(pin "D63"
		)
		(pin "D64"
		)
		(pin "D67"
		)
		(pin "D70"
		)
		(pin "B83"
		)
		(pin "D81"
		)
		(pin "D82"
		)
		(pin "B41"
		)
		(pin "D49"
		)
		(pin "D50"
		)
		(pin "A75"
		)
		(pin "D2"
		)
		(pin "D21"
		)
		(pin "C78"
		)
		(pin "C79"
		)
		(pin "B19"
		)
		(pin "B39"
		)
		(pin "A12"
		)
		(pin "B66"
		)
		(pin "D4"
		)
		(pin "D85"
		)
		(pin "D86"
		)
		(pin "A105"
		)
		(pin "B90"
		)
		(pin "A22"
		)
		(pin "A109"
		)
		(pin "B88"
		)
		(pin "B14"
		)
		(pin "B71"
		)
		(pin "B52"
		)
		(pin "B53"
		)
		(pin "D7"
		)
		(pin "A108"
		)
		(pin "C85"
		)
		(pin "C86"
		)
		(pin "B61"
		)
		(pin "B62"
		)
		(pin "D68"
		)
		(pin "D69"
		)
		(pin "A88"
		)
		(pin "A89"
		)
		(pin "D6"
		)
		(pin "C7"
		)
		(pin "B33"
		)
		(pin "D88"
		)
		(pin "D89"
		)
		(pin "B26"
		)
		(pin "A76"
		)
		(pin "D101"
		)
		(pin "D102"
		)
		(pin "B12"
		)
		(pin "C15"
		)
		(pin "C16"
		)
		(pin "A18"
		)
		(pin "A13"
		)
		(pin "A66"
		)
		(pin "C26"
		)
		(pin "C27"
		)
		(pin "A101"
		)
		(pin "A17"
		)
		(pin "B96"
		)
		(pin "C22"
		)
		(pin "C23"
		)
		(pin "A79"
		)
		(pin "A54"
		)
		(pin "C41"
		)
		(pin "C44"
		)
		(pin "A100"
		)
		(pin "A67"
		)
		(pin "A10"
		)
		(pin "A14"
		)
		(pin "C6"
		)
		(pin "A84"
		)
		(pin "B91"
		)
		(pin "C29"
		)
		(pin "C30"
		)
		(pin "A37"
		)
		(pin "A39"
		)
		(pin "B10"
		)
		(pin "B34"
		)
		(pin "C54"
		)
		(pin "C57"
		)
		(pin "B64"
		)
		(pin "B65"
		)
		(pin "A58"
		)
		(pin "A59"
		)
		(pin "B92"
		)
		(pin "C43"
		)
		(pin "C45"
		)
		(pin "A97"
		)
		(pin "A11"
		)
		(pin "A61"
		)
		(pin "A62"
		)
		(pin "B48"
		)
		(pin "B54"
		)
		(pin "D71"
		)
		(pin "D72"
		)
		(pin "A26"
		)
		(pin "A36"
		)
		(pin "D31"
		)
		(pin "D36"
		)
		(pin "B76"
		)
		(pin "B21"
		)
		(pin "B24"
		)
		(pin "B94"
		)
		(pin "D3"
		)
		(pin "B79"
		)
		(pin "A85"
		)
		(pin "A23"
		)
		(pin "A25"
		)
		(pin "A24"
		)
		(pin "D14"
		)
		(pin "D18"
		)
		(pin "B15"
		)
		(pin "A107"
		)
		(pin "A98"
		)
		(pin "D9"
		)
		(pin "B44"
		)
		(pin "A4"
		)
		(pin "C28"
		)
		(pin "C31"
		)
		(pin "A9"
		)
		(pin "C49"
		)
		(pin "C50"
		)
		(pin "A83"
		)
		(pin "A110"
		)
		(pin "D52"
		)
		(pin "D53"
		)
		(pin "A40"
		)
		(pin "A71"
		)
		(pin "D98"
		)
		(pin "D99"
		)
		(pin "D40"
		)
		(pin "D42"
		)
		(pin "D37"
		)
		(pin "D41"
		)
		(pin "C109"
		)
		(pin "C11"
		)
		(pin "A106"
		)
		(pin "A3"
		)
		(pin "B109"
		)
		(pin "B40"
		)
		(pin "C70"
		)
		(pin "C73"
		)
		(pin "D13"
		)
		(pin "A1"
		)
		(pin "A46"
		)
		(pin "A20"
		)
		(pin "A104"
		)
		(pin "C9"
		)
		(pin "C110"
		)
		(pin "C14"
		)
		(pin "B23"
		)
		(pin "A93"
		)
		(pin "B89"
		)
		(pin "B87"
		)
		(pin "D54"
		)
		(pin "D60"
		)
		(pin "A21"
		)
		(pin "B93"
		)
		(pin "A70"
		)
		(pin "A60"
		)
		(pin "B97"
		)
		(pin "B95"
		)
		(pin "D38"
		)
		(pin "D39"
		)
		(pin "A50"
		)
		(pin "A52"
		)
		(pin "A53"
		)
		(pin "D91"
		)
		(pin "D92"
		)
		(pin "C67"
		)
		(pin "D57"
		)
		(pin "A96"
		)
		(pin "A92"
		)
		(pin "B70"
		)
		(pin "C46"
		)
		(pin "C47"
		)
		(pin "B4"
		)
		(pin "A64"
		)
		(pin "A65"
		)
		(pin "B43"
		)
		(pin "C21"
		)
		(pin "C25"
		)
		(pin "B42"
		)
		(pin "C19"
		)
		(pin "C20"
		)
		(pin "C18"
		)
		(pin "C2"
		)
		(pin "C107"
		)
		(pin "C108"
		)
		(pin "B35"
		)
		(pin "A28"
		)
		(pin "B11"
		)
		(pin "A103"
		)
		(pin "C97"
		)
		(pin "D1"
		)
		(pin "B98"
		)
		(pin "A19"
		)
		(pin "A68"
		)
		(pin "A69"
		)
		(pin "B55"
		)
		(pin "B56"
		)
		(pin "A8"
		)
		(pin "A33"
		)
		(pin "A95"
		)
		(pin "D96"
		)
		(pin "D97"
		)
		(pin "B31"
		)
		(pin "B105"
		)
		(pin "B100"
		)
		(pin "C65"
		)
		(pin "C66"
		)
		(pin "B104"
		)
		(pin "D61"
		)
		(pin "D62"
		)
		(pin "D78"
		)
		(pin "D79"
		)
		(pin "C83"
		)
		(pin "C84"
		)
		(pin "D74"
		)
		(pin "D75"
		)
		(pin "A45"
		)
		(pin "D106"
		)
		(pin "D107"
		)
		(pin "C8"
		)
		(pin "C80"
		)
		(pin "C87"
		)
		(pin "C90"
		)
		(pin "D58"
		)
		(pin "D59"
		)
		(pin "D104"
		)
		(pin "D105"
		)
		(pin "C93"
		)
		(pin "C96"
		)
		(pin "B73"
		)
		(pin "D108"
		)
		(pin "D109"
		)
		(pin "B20"
		)
		(pin "A27"
		)
		(pin "D34"
		)
		(pin "D35"
		)
		(pin "C17"
		)
		(pin "C24"
		)
		(pin "B49"
		)
		(pin "A6"
		)
		(pin "B5"
		)
		(pin "B99"
		)
		(pin "B25"
		)
		(pin "D94"
		)
		(pin "D95"
		)
		(pin "B106"
		)
		(pin "B67"
		)
		(pin "A2"
		)
		(pin "B13"
		)
		(pin "A49"
		)
		(pin "C52"
		)
		(pin "C53"
		)
		(pin "B72"
		)
		(pin "C94"
		)
		(pin "C95"
		)
		(pin "B74"
		)
		(pin "D10"
		)
		(pin "B75"
		)
		(pin "B77"
		)
		(pin "C98"
		)
		(pin "C99"
		)
		(pin "A7"
		)
		(pin "C88"
		)
		(pin "C89"
		)
		(pin "C10"
		)
		(pin "B78"
		)
		(pin "B81"
		)
		(pin "B28"
		)
		(pin "A63"
		)
		(pin "C76"
		)
		(pin "C77"
		)
		(pin "A55"
		)
		(pin "A56"
		)
		(pin "C48"
		)
		(pin "C5"
		)
		(pin "A5"
		)
		(pin "C1"
		)
		(pin "C100"
		)
		(pin "B47"
		)
		(pin "C74"
		)
		(pin "C75"
		)
		(pin "C12"
		)
		(pin "B80"
		)
		(pin "D15"
		)
		(pin "D16"
		)
		(pin "D100"
		)
		(pin "D103"
		)
		(pin "B2"
		)
		(pin "B9"
		)
		(pin "A94"
		)
		(pin "B82"
		)
		(pin "D25"
		)
		(pin "D28"
		)
		(pin "B16"
		)
		(pin "D65"
		)
		(pin "D66"
		)
		(pin "D32"
		)
		(pin "D33"
		)
		(pin "B8"
		)
		(pin "B60"
		)
		(pin "A38"
		)
		(pin "A73"
		)
		(pin "A80"
		)
		(pin "B18"
		)
		(pin "MP"
		)
		(instances
			(project "com-express-7-baseboard"
				(path ""
					(reference "J12")
					(unit 1)
				)
			)
		)
	)
	(symbol
		(lib_id "antmicroB2BConnectors:Plug_Bus_CE7_EPT_401-51501-51")
		(at 281.94 33.02 0)
		(unit 11)
		(exclude_from_sim no)
		(in_bom yes)
		(on_board yes)
		(dnp no)
		(fields_autoplaced yes)
		(property "Reference" "J12"
			(at 262.89 25.4 0)
			(effects
				(font
					(size 1.27 1.27)
					(thickness 0.15)
				)
			)
		)
		(property "Value" "Plug_Bus_CE7_EPT_401-51501-51"
			(at 335.28 45.72 0)
			(effects
				(font
					(size 1.27 1.27)
					(thickness 0.15)
				)
				(justify left bottom)
				(hide yes)
			)
		)
		(property "Footprint" "antmicro-footprints:EPT_401-51501-51"
			(at 335.28 48.26 0)
			(effects
				(font
					(size 1.27 1.27)
					(thickness 0.15)
				)
				(justify left bottom)
				(hide yes)
			)
		)
		(property "Datasheet" "https://www.farnell.com/datasheets/1905093.pdf"
			(at 335.28 50.8 0)
			(effects
				(font
					(size 1.27 1.27)
					(thickness 0.15)
				)
				(justify left bottom)
				(hide yes)
			)
		)
		(property "Description" ""
			(at 281.94 33.02 0)
			(effects
				(font
					(size 1.27 1.27)
				)
				(hide yes)
			)
		)
		(property "Author" "Antmicro"
			(at 335.28 53.34 0)
			(effects
				(font
					(size 1.27 1.27)
					(thickness 0.15)
				)
				(justify left bottom)
				(hide yes)
			)
		)
		(property "License" "Apache-2.0"
			(at 335.28 55.88 0)
			(effects
				(font
					(size 1.27 1.27)
					(thickness 0.15)
				)
				(justify left bottom)
				(hide yes)
			)
		)
		(property "Manufacturer" "ept"
			(at 335.28 38.1 0)
			(effects
				(font
					(size 1.27 1.27)
					(thickness 0.15)
				)
				(justify left bottom)
				(hide yes)
			)
		)
		(property "MPN" "401-51501-51"
			(at 262.89 27.94 0)
			(effects
				(font
					(size 1.27 1.27)
					(thickness 0.15)
				)
			)
		)
		(pin "C91"
		)
		(pin "C92"
		)
		(pin "A15"
		)
		(pin "A91"
		)
		(pin "C34"
		)
		(pin "C35"
		)
		(pin "D22"
		)
		(pin "D23"
		)
		(pin "D55"
		)
		(pin "D56"
		)
		(pin "C55"
		)
		(pin "C56"
		)
		(pin "C71"
		)
		(pin "C72"
		)
		(pin "C32"
		)
		(pin "C33"
		)
		(pin "B6"
		)
		(pin "B58"
		)
		(pin "B59"
		)
		(pin "D5"
		)
		(pin "D51"
		)
		(pin "A29"
		)
		(pin "D46"
		)
		(pin "D47"
		)
		(pin "C105"
		)
		(pin "C106"
		)
		(pin "A16"
		)
		(pin "B22"
		)
		(pin "B51"
		)
		(pin "B30"
		)
		(pin "A44"
		)
		(pin "C51"
		)
		(pin "C60"
		)
		(pin "A81"
		)
		(pin "A82"
		)
		(pin "D90"
		)
		(pin "D93"
		)
		(pin "B68"
		)
		(pin "B69"
		)
		(pin "C103"
		)
		(pin "C104"
		)
		(pin "C58"
		)
		(pin "C59"
		)
		(pin "D84"
		)
		(pin "D87"
		)
		(pin "A30"
		)
		(pin "B29"
		)
		(pin "A41"
		)
		(pin "C40"
		)
		(pin "C42"
		)
		(pin "D80"
		)
		(pin "D83"
		)
		(pin "B103"
		)
		(pin "A102"
		)
		(pin "C101"
		)
		(pin "C102"
		)
		(pin "D11"
		)
		(pin "D110"
		)
		(pin "B37"
		)
		(pin "B45"
		)
		(pin "C61"
		)
		(pin "C62"
		)
		(pin "A42"
		)
		(pin "B36"
		)
		(pin "B57"
		)
		(pin "D12"
		)
		(pin "D44"
		)
		(pin "D48"
		)
		(pin "B32"
		)
		(pin "B107"
		)
		(pin "B108"
		)
		(pin "B110"
		)
		(pin "B101"
		)
		(pin "C63"
		)
		(pin "C64"
		)
		(pin "B50"
		)
		(pin "A87"
		)
		(pin "A86"
		)
		(pin "B27"
		)
		(pin "D17"
		)
		(pin "D24"
		)
		(pin "D26"
		)
		(pin "D27"
		)
		(pin "A47"
		)
		(pin "C81"
		)
		(pin "C82"
		)
		(pin "C68"
		)
		(pin "C69"
		)
		(pin "A74"
		)
		(pin "A48"
		)
		(pin "A57"
		)
		(pin "A43"
		)
		(pin "A31"
		)
		(pin "D29"
		)
		(pin "D30"
		)
		(pin "C36"
		)
		(pin "C37"
		)
		(pin "C3"
		)
		(pin "A35"
		)
		(pin "A34"
		)
		(pin "B7"
		)
		(pin "B46"
		)
		(pin "B1"
		)
		(pin "B63"
		)
		(pin "A51"
		)
		(pin "A99"
		)
		(pin "B17"
		)
		(pin "C13"
		)
		(pin "C4"
		)
		(pin "B102"
		)
		(pin "C38"
		)
		(pin "C39"
		)
		(pin "B3"
		)
		(pin "A90"
		)
		(pin "A72"
		)
		(pin "B84"
		)
		(pin "D19"
		)
		(pin "D20"
		)
		(pin "D43"
		)
		(pin "D45"
		)
		(pin "A77"
		)
		(pin "A78"
		)
		(pin "B38"
		)
		(pin "B86"
		)
		(pin "D77"
		)
		(pin "D8"
		)
		(pin "A32"
		)
		(pin "B85"
		)
		(pin "D73"
		)
		(pin "D76"
		)
		(pin "D63"
		)
		(pin "D64"
		)
		(pin "D67"
		)
		(pin "D70"
		)
		(pin "B83"
		)
		(pin "D81"
		)
		(pin "D82"
		)
		(pin "B41"
		)
		(pin "D49"
		)
		(pin "D50"
		)
		(pin "A75"
		)
		(pin "D2"
		)
		(pin "D21"
		)
		(pin "C78"
		)
		(pin "C79"
		)
		(pin "B19"
		)
		(pin "B39"
		)
		(pin "A12"
		)
		(pin "B66"
		)
		(pin "D4"
		)
		(pin "D85"
		)
		(pin "D86"
		)
		(pin "A105"
		)
		(pin "B90"
		)
		(pin "A22"
		)
		(pin "A109"
		)
		(pin "B88"
		)
		(pin "B14"
		)
		(pin "B71"
		)
		(pin "B52"
		)
		(pin "B53"
		)
		(pin "D7"
		)
		(pin "A108"
		)
		(pin "C85"
		)
		(pin "C86"
		)
		(pin "B61"
		)
		(pin "B62"
		)
		(pin "D68"
		)
		(pin "D69"
		)
		(pin "A88"
		)
		(pin "A89"
		)
		(pin "D6"
		)
		(pin "C7"
		)
		(pin "B33"
		)
		(pin "D88"
		)
		(pin "D89"
		)
		(pin "B26"
		)
		(pin "A76"
		)
		(pin "D101"
		)
		(pin "D102"
		)
		(pin "B12"
		)
		(pin "C15"
		)
		(pin "C16"
		)
		(pin "A18"
		)
		(pin "A13"
		)
		(pin "A66"
		)
		(pin "C26"
		)
		(pin "C27"
		)
		(pin "A101"
		)
		(pin "A17"
		)
		(pin "B96"
		)
		(pin "C22"
		)
		(pin "C23"
		)
		(pin "A79"
		)
		(pin "A54"
		)
		(pin "C41"
		)
		(pin "C44"
		)
		(pin "A100"
		)
		(pin "A67"
		)
		(pin "A10"
		)
		(pin "A14"
		)
		(pin "C6"
		)
		(pin "A84"
		)
		(pin "B91"
		)
		(pin "C29"
		)
		(pin "C30"
		)
		(pin "A37"
		)
		(pin "A39"
		)
		(pin "B10"
		)
		(pin "B34"
		)
		(pin "C54"
		)
		(pin "C57"
		)
		(pin "B64"
		)
		(pin "B65"
		)
		(pin "A58"
		)
		(pin "A59"
		)
		(pin "B92"
		)
		(pin "C43"
		)
		(pin "C45"
		)
		(pin "A97"
		)
		(pin "A11"
		)
		(pin "A61"
		)
		(pin "A62"
		)
		(pin "B48"
		)
		(pin "B54"
		)
		(pin "D71"
		)
		(pin "D72"
		)
		(pin "A26"
		)
		(pin "A36"
		)
		(pin "D31"
		)
		(pin "D36"
		)
		(pin "B76"
		)
		(pin "B21"
		)
		(pin "B24"
		)
		(pin "B94"
		)
		(pin "D3"
		)
		(pin "B79"
		)
		(pin "A85"
		)
		(pin "A23"
		)
		(pin "A25"
		)
		(pin "A24"
		)
		(pin "D14"
		)
		(pin "D18"
		)
		(pin "B15"
		)
		(pin "A107"
		)
		(pin "A98"
		)
		(pin "D9"
		)
		(pin "B44"
		)
		(pin "A4"
		)
		(pin "C28"
		)
		(pin "C31"
		)
		(pin "A9"
		)
		(pin "C49"
		)
		(pin "C50"
		)
		(pin "A83"
		)
		(pin "A110"
		)
		(pin "D52"
		)
		(pin "D53"
		)
		(pin "A40"
		)
		(pin "A71"
		)
		(pin "D98"
		)
		(pin "D99"
		)
		(pin "D40"
		)
		(pin "D42"
		)
		(pin "D37"
		)
		(pin "D41"
		)
		(pin "C109"
		)
		(pin "C11"
		)
		(pin "A106"
		)
		(pin "A3"
		)
		(pin "B109"
		)
		(pin "B40"
		)
		(pin "C70"
		)
		(pin "C73"
		)
		(pin "D13"
		)
		(pin "A1"
		)
		(pin "A46"
		)
		(pin "A20"
		)
		(pin "A104"
		)
		(pin "C9"
		)
		(pin "C110"
		)
		(pin "C14"
		)
		(pin "B23"
		)
		(pin "A93"
		)
		(pin "B89"
		)
		(pin "B87"
		)
		(pin "D54"
		)
		(pin "D60"
		)
		(pin "A21"
		)
		(pin "B93"
		)
		(pin "A70"
		)
		(pin "A60"
		)
		(pin "B97"
		)
		(pin "B95"
		)
		(pin "D38"
		)
		(pin "D39"
		)
		(pin "A50"
		)
		(pin "A52"
		)
		(pin "A53"
		)
		(pin "D91"
		)
		(pin "D92"
		)
		(pin "C67"
		)
		(pin "D57"
		)
		(pin "A96"
		)
		(pin "A92"
		)
		(pin "B70"
		)
		(pin "C46"
		)
		(pin "C47"
		)
		(pin "B4"
		)
		(pin "A64"
		)
		(pin "A65"
		)
		(pin "B43"
		)
		(pin "C21"
		)
		(pin "C25"
		)
		(pin "B42"
		)
		(pin "C19"
		)
		(pin "C20"
		)
		(pin "C18"
		)
		(pin "C2"
		)
		(pin "C107"
		)
		(pin "C108"
		)
		(pin "B35"
		)
		(pin "A28"
		)
		(pin "B11"
		)
		(pin "A103"
		)
		(pin "C97"
		)
		(pin "D1"
		)
		(pin "B98"
		)
		(pin "A19"
		)
		(pin "A68"
		)
		(pin "A69"
		)
		(pin "B55"
		)
		(pin "B56"
		)
		(pin "A8"
		)
		(pin "A33"
		)
		(pin "A95"
		)
		(pin "D96"
		)
		(pin "D97"
		)
		(pin "B31"
		)
		(pin "B105"
		)
		(pin "B100"
		)
		(pin "C65"
		)
		(pin "C66"
		)
		(pin "B104"
		)
		(pin "D61"
		)
		(pin "D62"
		)
		(pin "D78"
		)
		(pin "D79"
		)
		(pin "C83"
		)
		(pin "C84"
		)
		(pin "D74"
		)
		(pin "D75"
		)
		(pin "A45"
		)
		(pin "D106"
		)
		(pin "D107"
		)
		(pin "C8"
		)
		(pin "C80"
		)
		(pin "C87"
		)
		(pin "C90"
		)
		(pin "D58"
		)
		(pin "D59"
		)
		(pin "D104"
		)
		(pin "D105"
		)
		(pin "C93"
		)
		(pin "C96"
		)
		(pin "B73"
		)
		(pin "D108"
		)
		(pin "D109"
		)
		(pin "B20"
		)
		(pin "A27"
		)
		(pin "D34"
		)
		(pin "D35"
		)
		(pin "C17"
		)
		(pin "C24"
		)
		(pin "B49"
		)
		(pin "A6"
		)
		(pin "B5"
		)
		(pin "B99"
		)
		(pin "B25"
		)
		(pin "D94"
		)
		(pin "D95"
		)
		(pin "B106"
		)
		(pin "B67"
		)
		(pin "A2"
		)
		(pin "B13"
		)
		(pin "A49"
		)
		(pin "C52"
		)
		(pin "C53"
		)
		(pin "B72"
		)
		(pin "C94"
		)
		(pin "C95"
		)
		(pin "B74"
		)
		(pin "D10"
		)
		(pin "B75"
		)
		(pin "B77"
		)
		(pin "C98"
		)
		(pin "C99"
		)
		(pin "A7"
		)
		(pin "C88"
		)
		(pin "C89"
		)
		(pin "C10"
		)
		(pin "B78"
		)
		(pin "B81"
		)
		(pin "B28"
		)
		(pin "A63"
		)
		(pin "C76"
		)
		(pin "C77"
		)
		(pin "A55"
		)
		(pin "A56"
		)
		(pin "C48"
		)
		(pin "C5"
		)
		(pin "A5"
		)
		(pin "C1"
		)
		(pin "C100"
		)
		(pin "B47"
		)
		(pin "C74"
		)
		(pin "C75"
		)
		(pin "C12"
		)
		(pin "B80"
		)
		(pin "D15"
		)
		(pin "D16"
		)
		(pin "D100"
		)
		(pin "D103"
		)
		(pin "B2"
		)
		(pin "B9"
		)
		(pin "A94"
		)
		(pin "B82"
		)
		(pin "D25"
		)
		(pin "D28"
		)
		(pin "B16"
		)
		(pin "D65"
		)
		(pin "D66"
		)
		(pin "D32"
		)
		(pin "D33"
		)
		(pin "B8"
		)
		(pin "B60"
		)
		(pin "A38"
		)
		(pin "A73"
		)
		(pin "A80"
		)
		(pin "B18"
		)
		(pin "MP"
		)
		(instances
			(project "com-express-7-baseboard"
				(path ""
					(reference "J12")
					(unit 11)
				)
			)
		)
	)
	(symbol
		(lib_id "antmicroB2BConnectors:Plug_Bus_CE7_EPT_401-51501-51")
		(at 139.7 210.82 0)
		(unit 2)
		(exclude_from_sim no)
		(in_bom yes)
		(on_board yes)
		(dnp no)
		(fields_autoplaced yes)
		(property "Reference" "J12"
			(at 120.65 203.2 0)
			(effects
				(font
					(size 1.27 1.27)
					(thickness 0.15)
				)
			)
		)
		(property "Value" "Plug_Bus_CE7_EPT_401-51501-51"
			(at 193.04 223.52 0)
			(effects
				(font
					(size 1.27 1.27)
					(thickness 0.15)
				)
				(justify left bottom)
				(hide yes)
			)
		)
		(property "Footprint" "antmicro-footprints:EPT_401-51501-51"
			(at 193.04 226.06 0)
			(effects
				(font
					(size 1.27 1.27)
					(thickness 0.15)
				)
				(justify left bottom)
				(hide yes)
			)
		)
		(property "Datasheet" "https://www.farnell.com/datasheets/1905093.pdf"
			(at 193.04 228.6 0)
			(effects
				(font
					(size 1.27 1.27)
					(thickness 0.15)
				)
				(justify left bottom)
				(hide yes)
			)
		)
		(property "Description" ""
			(at 139.7 210.82 0)
			(effects
				(font
					(size 1.27 1.27)
				)
				(hide yes)
			)
		)
		(property "Author" "Antmicro"
			(at 193.04 231.14 0)
			(effects
				(font
					(size 1.27 1.27)
					(thickness 0.15)
				)
				(justify left bottom)
				(hide yes)
			)
		)
		(property "License" "Apache-2.0"
			(at 193.04 233.68 0)
			(effects
				(font
					(size 1.27 1.27)
					(thickness 0.15)
				)
				(justify left bottom)
				(hide yes)
			)
		)
		(property "Manufacturer" "ept"
			(at 193.04 215.9 0)
			(effects
				(font
					(size 1.27 1.27)
					(thickness 0.15)
				)
				(justify left bottom)
				(hide yes)
			)
		)
		(property "MPN" "401-51501-51"
			(at 120.65 205.74 0)
			(effects
				(font
					(size 1.27 1.27)
					(thickness 0.15)
				)
			)
		)
		(pin "C91"
		)
		(pin "C92"
		)
		(pin "A15"
		)
		(pin "A91"
		)
		(pin "C34"
		)
		(pin "C35"
		)
		(pin "D22"
		)
		(pin "D23"
		)
		(pin "D55"
		)
		(pin "D56"
		)
		(pin "C55"
		)
		(pin "C56"
		)
		(pin "C71"
		)
		(pin "C72"
		)
		(pin "C32"
		)
		(pin "C33"
		)
		(pin "B6"
		)
		(pin "B58"
		)
		(pin "B59"
		)
		(pin "D5"
		)
		(pin "D51"
		)
		(pin "A29"
		)
		(pin "D46"
		)
		(pin "D47"
		)
		(pin "C105"
		)
		(pin "C106"
		)
		(pin "A16"
		)
		(pin "B22"
		)
		(pin "B51"
		)
		(pin "B30"
		)
		(pin "A44"
		)
		(pin "C51"
		)
		(pin "C60"
		)
		(pin "A81"
		)
		(pin "A82"
		)
		(pin "D90"
		)
		(pin "D93"
		)
		(pin "B68"
		)
		(pin "B69"
		)
		(pin "C103"
		)
		(pin "C104"
		)
		(pin "C58"
		)
		(pin "C59"
		)
		(pin "D84"
		)
		(pin "D87"
		)
		(pin "A30"
		)
		(pin "B29"
		)
		(pin "A41"
		)
		(pin "C40"
		)
		(pin "C42"
		)
		(pin "D80"
		)
		(pin "D83"
		)
		(pin "B103"
		)
		(pin "A102"
		)
		(pin "C101"
		)
		(pin "C102"
		)
		(pin "D11"
		)
		(pin "D110"
		)
		(pin "B37"
		)
		(pin "B45"
		)
		(pin "C61"
		)
		(pin "C62"
		)
		(pin "A42"
		)
		(pin "B36"
		)
		(pin "B57"
		)
		(pin "D12"
		)
		(pin "D44"
		)
		(pin "D48"
		)
		(pin "B32"
		)
		(pin "B107"
		)
		(pin "B108"
		)
		(pin "B110"
		)
		(pin "B101"
		)
		(pin "C63"
		)
		(pin "C64"
		)
		(pin "B50"
		)
		(pin "A87"
		)
		(pin "A86"
		)
		(pin "B27"
		)
		(pin "D17"
		)
		(pin "D24"
		)
		(pin "D26"
		)
		(pin "D27"
		)
		(pin "A47"
		)
		(pin "C81"
		)
		(pin "C82"
		)
		(pin "C68"
		)
		(pin "C69"
		)
		(pin "A74"
		)
		(pin "A48"
		)
		(pin "A57"
		)
		(pin "A43"
		)
		(pin "A31"
		)
		(pin "D29"
		)
		(pin "D30"
		)
		(pin "C36"
		)
		(pin "C37"
		)
		(pin "C3"
		)
		(pin "A35"
		)
		(pin "A34"
		)
		(pin "B7"
		)
		(pin "B46"
		)
		(pin "B1"
		)
		(pin "B63"
		)
		(pin "A51"
		)
		(pin "A99"
		)
		(pin "B17"
		)
		(pin "C13"
		)
		(pin "C4"
		)
		(pin "B102"
		)
		(pin "C38"
		)
		(pin "C39"
		)
		(pin "B3"
		)
		(pin "A90"
		)
		(pin "A72"
		)
		(pin "B84"
		)
		(pin "D19"
		)
		(pin "D20"
		)
		(pin "D43"
		)
		(pin "D45"
		)
		(pin "A77"
		)
		(pin "A78"
		)
		(pin "B38"
		)
		(pin "B86"
		)
		(pin "D77"
		)
		(pin "D8"
		)
		(pin "A32"
		)
		(pin "B85"
		)
		(pin "D73"
		)
		(pin "D76"
		)
		(pin "D63"
		)
		(pin "D64"
		)
		(pin "D67"
		)
		(pin "D70"
		)
		(pin "B83"
		)
		(pin "D81"
		)
		(pin "D82"
		)
		(pin "B41"
		)
		(pin "D49"
		)
		(pin "D50"
		)
		(pin "A75"
		)
		(pin "D2"
		)
		(pin "D21"
		)
		(pin "C78"
		)
		(pin "C79"
		)
		(pin "B19"
		)
		(pin "B39"
		)
		(pin "A12"
		)
		(pin "B66"
		)
		(pin "D4"
		)
		(pin "D85"
		)
		(pin "D86"
		)
		(pin "A105"
		)
		(pin "B90"
		)
		(pin "A22"
		)
		(pin "A109"
		)
		(pin "B88"
		)
		(pin "B14"
		)
		(pin "B71"
		)
		(pin "B52"
		)
		(pin "B53"
		)
		(pin "D7"
		)
		(pin "A108"
		)
		(pin "C85"
		)
		(pin "C86"
		)
		(pin "B61"
		)
		(pin "B62"
		)
		(pin "D68"
		)
		(pin "D69"
		)
		(pin "A88"
		)
		(pin "A89"
		)
		(pin "D6"
		)
		(pin "C7"
		)
		(pin "B33"
		)
		(pin "D88"
		)
		(pin "D89"
		)
		(pin "B26"
		)
		(pin "A76"
		)
		(pin "D101"
		)
		(pin "D102"
		)
		(pin "B12"
		)
		(pin "C15"
		)
		(pin "C16"
		)
		(pin "A18"
		)
		(pin "A13"
		)
		(pin "A66"
		)
		(pin "C26"
		)
		(pin "C27"
		)
		(pin "A101"
		)
		(pin "A17"
		)
		(pin "B96"
		)
		(pin "C22"
		)
		(pin "C23"
		)
		(pin "A79"
		)
		(pin "A54"
		)
		(pin "C41"
		)
		(pin "C44"
		)
		(pin "A100"
		)
		(pin "A67"
		)
		(pin "A10"
		)
		(pin "A14"
		)
		(pin "C6"
		)
		(pin "A84"
		)
		(pin "B91"
		)
		(pin "C29"
		)
		(pin "C30"
		)
		(pin "A37"
		)
		(pin "A39"
		)
		(pin "B10"
		)
		(pin "B34"
		)
		(pin "C54"
		)
		(pin "C57"
		)
		(pin "B64"
		)
		(pin "B65"
		)
		(pin "A58"
		)
		(pin "A59"
		)
		(pin "B92"
		)
		(pin "C43"
		)
		(pin "C45"
		)
		(pin "A97"
		)
		(pin "A11"
		)
		(pin "A61"
		)
		(pin "A62"
		)
		(pin "B48"
		)
		(pin "B54"
		)
		(pin "D71"
		)
		(pin "D72"
		)
		(pin "A26"
		)
		(pin "A36"
		)
		(pin "D31"
		)
		(pin "D36"
		)
		(pin "B76"
		)
		(pin "B21"
		)
		(pin "B24"
		)
		(pin "B94"
		)
		(pin "D3"
		)
		(pin "B79"
		)
		(pin "A85"
		)
		(pin "A23"
		)
		(pin "A25"
		)
		(pin "A24"
		)
		(pin "D14"
		)
		(pin "D18"
		)
		(pin "B15"
		)
		(pin "A107"
		)
		(pin "A98"
		)
		(pin "D9"
		)
		(pin "B44"
		)
		(pin "A4"
		)
		(pin "C28"
		)
		(pin "C31"
		)
		(pin "A9"
		)
		(pin "C49"
		)
		(pin "C50"
		)
		(pin "A83"
		)
		(pin "A110"
		)
		(pin "D52"
		)
		(pin "D53"
		)
		(pin "A40"
		)
		(pin "A71"
		)
		(pin "D98"
		)
		(pin "D99"
		)
		(pin "D40"
		)
		(pin "D42"
		)
		(pin "D37"
		)
		(pin "D41"
		)
		(pin "C109"
		)
		(pin "C11"
		)
		(pin "A106"
		)
		(pin "A3"
		)
		(pin "B109"
		)
		(pin "B40"
		)
		(pin "C70"
		)
		(pin "C73"
		)
		(pin "D13"
		)
		(pin "A1"
		)
		(pin "A46"
		)
		(pin "A20"
		)
		(pin "A104"
		)
		(pin "C9"
		)
		(pin "C110"
		)
		(pin "C14"
		)
		(pin "B23"
		)
		(pin "A93"
		)
		(pin "B89"
		)
		(pin "B87"
		)
		(pin "D54"
		)
		(pin "D60"
		)
		(pin "A21"
		)
		(pin "B93"
		)
		(pin "A70"
		)
		(pin "A60"
		)
		(pin "B97"
		)
		(pin "B95"
		)
		(pin "D38"
		)
		(pin "D39"
		)
		(pin "A50"
		)
		(pin "A52"
		)
		(pin "A53"
		)
		(pin "D91"
		)
		(pin "D92"
		)
		(pin "C67"
		)
		(pin "D57"
		)
		(pin "A96"
		)
		(pin "A92"
		)
		(pin "B70"
		)
		(pin "C46"
		)
		(pin "C47"
		)
		(pin "B4"
		)
		(pin "A64"
		)
		(pin "A65"
		)
		(pin "B43"
		)
		(pin "C21"
		)
		(pin "C25"
		)
		(pin "B42"
		)
		(pin "C19"
		)
		(pin "C20"
		)
		(pin "C18"
		)
		(pin "C2"
		)
		(pin "C107"
		)
		(pin "C108"
		)
		(pin "B35"
		)
		(pin "A28"
		)
		(pin "B11"
		)
		(pin "A103"
		)
		(pin "C97"
		)
		(pin "D1"
		)
		(pin "B98"
		)
		(pin "A19"
		)
		(pin "A68"
		)
		(pin "A69"
		)
		(pin "B55"
		)
		(pin "B56"
		)
		(pin "A8"
		)
		(pin "A33"
		)
		(pin "A95"
		)
		(pin "D96"
		)
		(pin "D97"
		)
		(pin "B31"
		)
		(pin "B105"
		)
		(pin "B100"
		)
		(pin "C65"
		)
		(pin "C66"
		)
		(pin "B104"
		)
		(pin "D61"
		)
		(pin "D62"
		)
		(pin "D78"
		)
		(pin "D79"
		)
		(pin "C83"
		)
		(pin "C84"
		)
		(pin "D74"
		)
		(pin "D75"
		)
		(pin "A45"
		)
		(pin "D106"
		)
		(pin "D107"
		)
		(pin "C8"
		)
		(pin "C80"
		)
		(pin "C87"
		)
		(pin "C90"
		)
		(pin "D58"
		)
		(pin "D59"
		)
		(pin "D104"
		)
		(pin "D105"
		)
		(pin "C93"
		)
		(pin "C96"
		)
		(pin "B73"
		)
		(pin "D108"
		)
		(pin "D109"
		)
		(pin "B20"
		)
		(pin "A27"
		)
		(pin "D34"
		)
		(pin "D35"
		)
		(pin "C17"
		)
		(pin "C24"
		)
		(pin "B49"
		)
		(pin "A6"
		)
		(pin "B5"
		)
		(pin "B99"
		)
		(pin "B25"
		)
		(pin "D94"
		)
		(pin "D95"
		)
		(pin "B106"
		)
		(pin "B67"
		)
		(pin "A2"
		)
		(pin "B13"
		)
		(pin "A49"
		)
		(pin "C52"
		)
		(pin "C53"
		)
		(pin "B72"
		)
		(pin "C94"
		)
		(pin "C95"
		)
		(pin "B74"
		)
		(pin "D10"
		)
		(pin "B75"
		)
		(pin "B77"
		)
		(pin "C98"
		)
		(pin "C99"
		)
		(pin "A7"
		)
		(pin "C88"
		)
		(pin "C89"
		)
		(pin "C10"
		)
		(pin "B78"
		)
		(pin "B81"
		)
		(pin "B28"
		)
		(pin "A63"
		)
		(pin "C76"
		)
		(pin "C77"
		)
		(pin "A55"
		)
		(pin "A56"
		)
		(pin "C48"
		)
		(pin "C5"
		)
		(pin "A5"
		)
		(pin "C1"
		)
		(pin "C100"
		)
		(pin "B47"
		)
		(pin "C74"
		)
		(pin "C75"
		)
		(pin "C12"
		)
		(pin "B80"
		)
		(pin "D15"
		)
		(pin "D16"
		)
		(pin "D100"
		)
		(pin "D103"
		)
		(pin "B2"
		)
		(pin "B9"
		)
		(pin "A94"
		)
		(pin "B82"
		)
		(pin "D25"
		)
		(pin "D28"
		)
		(pin "B16"
		)
		(pin "D65"
		)
		(pin "D66"
		)
		(pin "D32"
		)
		(pin "D33"
		)
		(pin "B8"
		)
		(pin "B60"
		)
		(pin "A38"
		)
		(pin "A73"
		)
		(pin "A80"
		)
		(pin "B18"
		)
		(pin "MP"
		)
		(instances
			(project "com-express-7-baseboard"
				(path ""
					(reference "J12")
					(unit 2)
				)
			)
		)
	)
	(symbol
		(lib_id "antmicroTestPoints:TP_0.75mm_SMD")
		(at 281.94 175.26 0)
		(unit 1)
		(exclude_from_sim no)
		(in_bom no)
		(on_board yes)
		(dnp no)
		(fields_autoplaced yes)
		(property "Reference" "TP20"
			(at 287.02 175.26 0)
			(effects
				(font
					(size 1.27 1.27)
					(thickness 0.15)
				)
				(justify left)
			)
		)
		(property "Value" "TP_0.75mm_SMD"
			(at 292.735 179.07 0)
			(effects
				(font
					(size 1.27 1.27)
					(thickness 0.15)
				)
				(justify left bottom)
				(hide yes)
			)
		)
		(property "Footprint" "antmicro-footprints:TP_SMD_0.75mm"
			(at 292.735 181.61 0)
			(effects
				(font
					(size 1.27 1.27)
					(thickness 0.15)
				)
				(justify left bottom)
				(hide yes)
			)
		)
		(property "Datasheet" ""
			(at 299.72 187.96 0)
			(effects
				(font
					(size 1.27 1.27)
					(thickness 0.15)
				)
				(justify left bottom)
				(hide yes)
			)
		)
		(property "Description" ""
			(at 281.94 175.26 0)
			(effects
				(font
					(size 1.27 1.27)
				)
				(hide yes)
			)
		)
		(property "MPN" ""
			(at 292.735 186.69 0)
			(effects
				(font
					(size 1.27 1.27)
					(thickness 0.15)
				)
				(justify left bottom)
				(hide yes)
			)
		)
		(property "Manufacturer" ""
			(at 292.735 181.61 0)
			(effects
				(font
					(size 1.27 1.27)
					(thickness 0.15)
				)
				(justify left bottom)
				(hide yes)
			)
		)
		(property "Author" "Antmicro"
			(at 292.735 184.15 0)
			(effects
				(font
					(size 1.27 1.27)
					(thickness 0.15)
				)
				(justify left bottom)
				(hide yes)
			)
		)
		(property "License" "Apache-2.0"
			(at 292.735 186.69 0)
			(effects
				(font
					(size 1.27 1.27)
					(thickness 0.15)
				)
				(justify left bottom)
				(hide yes)
			)
		)
		(property "Public" "False"
			(at 292.1 189.23 0)
			(effects
				(font
					(size 1.27 1.27)
				)
				(justify left bottom)
				(hide yes)
			)
		)
		(pin "1"
		)
		(instances
			(project "com-express-7-baseboard"
				(path ""
					(reference "TP20")
					(unit 1)
				)
			)
		)
	)
	(symbol
		(lib_id "antmicroB2BConnectors:Plug_Bus_CE7_EPT_401-51501-51")
		(at 355.6 33.02 0)
		(unit 6)
		(exclude_from_sim no)
		(in_bom yes)
		(on_board yes)
		(dnp no)
		(fields_autoplaced yes)
		(property "Reference" "J12"
			(at 336.55 25.4 0)
			(effects
				(font
					(size 1.27 1.27)
					(thickness 0.15)
				)
			)
		)
		(property "Value" "Plug_Bus_CE7_EPT_401-51501-51"
			(at 408.94 45.72 0)
			(effects
				(font
					(size 1.27 1.27)
					(thickness 0.15)
				)
				(justify left bottom)
				(hide yes)
			)
		)
		(property "Footprint" "antmicro-footprints:EPT_401-51501-51"
			(at 408.94 48.26 0)
			(effects
				(font
					(size 1.27 1.27)
					(thickness 0.15)
				)
				(justify left bottom)
				(hide yes)
			)
		)
		(property "Datasheet" "https://www.farnell.com/datasheets/1905093.pdf"
			(at 408.94 50.8 0)
			(effects
				(font
					(size 1.27 1.27)
					(thickness 0.15)
				)
				(justify left bottom)
				(hide yes)
			)
		)
		(property "Description" ""
			(at 355.6 33.02 0)
			(effects
				(font
					(size 1.27 1.27)
				)
				(hide yes)
			)
		)
		(property "Author" "Antmicro"
			(at 408.94 53.34 0)
			(effects
				(font
					(size 1.27 1.27)
					(thickness 0.15)
				)
				(justify left bottom)
				(hide yes)
			)
		)
		(property "License" "Apache-2.0"
			(at 408.94 55.88 0)
			(effects
				(font
					(size 1.27 1.27)
					(thickness 0.15)
				)
				(justify left bottom)
				(hide yes)
			)
		)
		(property "Manufacturer" "ept"
			(at 408.94 38.1 0)
			(effects
				(font
					(size 1.27 1.27)
					(thickness 0.15)
				)
				(justify left bottom)
				(hide yes)
			)
		)
		(property "MPN" "401-51501-51"
			(at 336.55 27.94 0)
			(effects
				(font
					(size 1.27 1.27)
					(thickness 0.15)
				)
			)
		)
		(pin "C91"
		)
		(pin "C92"
		)
		(pin "A15"
		)
		(pin "A91"
		)
		(pin "C34"
		)
		(pin "C35"
		)
		(pin "D22"
		)
		(pin "D23"
		)
		(pin "D55"
		)
		(pin "D56"
		)
		(pin "C55"
		)
		(pin "C56"
		)
		(pin "C71"
		)
		(pin "C72"
		)
		(pin "C32"
		)
		(pin "C33"
		)
		(pin "B6"
		)
		(pin "B58"
		)
		(pin "B59"
		)
		(pin "D5"
		)
		(pin "D51"
		)
		(pin "A29"
		)
		(pin "D46"
		)
		(pin "D47"
		)
		(pin "C105"
		)
		(pin "C106"
		)
		(pin "A16"
		)
		(pin "B22"
		)
		(pin "B51"
		)
		(pin "B30"
		)
		(pin "A44"
		)
		(pin "C51"
		)
		(pin "C60"
		)
		(pin "A81"
		)
		(pin "A82"
		)
		(pin "D90"
		)
		(pin "D93"
		)
		(pin "B68"
		)
		(pin "B69"
		)
		(pin "C103"
		)
		(pin "C104"
		)
		(pin "C58"
		)
		(pin "C59"
		)
		(pin "D84"
		)
		(pin "D87"
		)
		(pin "A30"
		)
		(pin "B29"
		)
		(pin "A41"
		)
		(pin "C40"
		)
		(pin "C42"
		)
		(pin "D80"
		)
		(pin "D83"
		)
		(pin "B103"
		)
		(pin "A102"
		)
		(pin "C101"
		)
		(pin "C102"
		)
		(pin "D11"
		)
		(pin "D110"
		)
		(pin "B37"
		)
		(pin "B45"
		)
		(pin "C61"
		)
		(pin "C62"
		)
		(pin "A42"
		)
		(pin "B36"
		)
		(pin "B57"
		)
		(pin "D12"
		)
		(pin "D44"
		)
		(pin "D48"
		)
		(pin "B32"
		)
		(pin "B107"
		)
		(pin "B108"
		)
		(pin "B110"
		)
		(pin "B101"
		)
		(pin "C63"
		)
		(pin "C64"
		)
		(pin "B50"
		)
		(pin "A87"
		)
		(pin "A86"
		)
		(pin "B27"
		)
		(pin "D17"
		)
		(pin "D24"
		)
		(pin "D26"
		)
		(pin "D27"
		)
		(pin "A47"
		)
		(pin "C81"
		)
		(pin "C82"
		)
		(pin "C68"
		)
		(pin "C69"
		)
		(pin "A74"
		)
		(pin "A48"
		)
		(pin "A57"
		)
		(pin "A43"
		)
		(pin "A31"
		)
		(pin "D29"
		)
		(pin "D30"
		)
		(pin "C36"
		)
		(pin "C37"
		)
		(pin "C3"
		)
		(pin "A35"
		)
		(pin "A34"
		)
		(pin "B7"
		)
		(pin "B46"
		)
		(pin "B1"
		)
		(pin "B63"
		)
		(pin "A51"
		)
		(pin "A99"
		)
		(pin "B17"
		)
		(pin "C13"
		)
		(pin "C4"
		)
		(pin "B102"
		)
		(pin "C38"
		)
		(pin "C39"
		)
		(pin "B3"
		)
		(pin "A90"
		)
		(pin "A72"
		)
		(pin "B84"
		)
		(pin "D19"
		)
		(pin "D20"
		)
		(pin "D43"
		)
		(pin "D45"
		)
		(pin "A77"
		)
		(pin "A78"
		)
		(pin "B38"
		)
		(pin "B86"
		)
		(pin "D77"
		)
		(pin "D8"
		)
		(pin "A32"
		)
		(pin "B85"
		)
		(pin "D73"
		)
		(pin "D76"
		)
		(pin "D63"
		)
		(pin "D64"
		)
		(pin "D67"
		)
		(pin "D70"
		)
		(pin "B83"
		)
		(pin "D81"
		)
		(pin "D82"
		)
		(pin "B41"
		)
		(pin "D49"
		)
		(pin "D50"
		)
		(pin "A75"
		)
		(pin "D2"
		)
		(pin "D21"
		)
		(pin "C78"
		)
		(pin "C79"
		)
		(pin "B19"
		)
		(pin "B39"
		)
		(pin "A12"
		)
		(pin "B66"
		)
		(pin "D4"
		)
		(pin "D85"
		)
		(pin "D86"
		)
		(pin "A105"
		)
		(pin "B90"
		)
		(pin "A22"
		)
		(pin "A109"
		)
		(pin "B88"
		)
		(pin "B14"
		)
		(pin "B71"
		)
		(pin "B52"
		)
		(pin "B53"
		)
		(pin "D7"
		)
		(pin "A108"
		)
		(pin "C85"
		)
		(pin "C86"
		)
		(pin "B61"
		)
		(pin "B62"
		)
		(pin "D68"
		)
		(pin "D69"
		)
		(pin "A88"
		)
		(pin "A89"
		)
		(pin "D6"
		)
		(pin "C7"
		)
		(pin "B33"
		)
		(pin "D88"
		)
		(pin "D89"
		)
		(pin "B26"
		)
		(pin "A76"
		)
		(pin "D101"
		)
		(pin "D102"
		)
		(pin "B12"
		)
		(pin "C15"
		)
		(pin "C16"
		)
		(pin "A18"
		)
		(pin "A13"
		)
		(pin "A66"
		)
		(pin "C26"
		)
		(pin "C27"
		)
		(pin "A101"
		)
		(pin "A17"
		)
		(pin "B96"
		)
		(pin "C22"
		)
		(pin "C23"
		)
		(pin "A79"
		)
		(pin "A54"
		)
		(pin "C41"
		)
		(pin "C44"
		)
		(pin "A100"
		)
		(pin "A67"
		)
		(pin "A10"
		)
		(pin "A14"
		)
		(pin "C6"
		)
		(pin "A84"
		)
		(pin "B91"
		)
		(pin "C29"
		)
		(pin "C30"
		)
		(pin "A37"
		)
		(pin "A39"
		)
		(pin "B10"
		)
		(pin "B34"
		)
		(pin "C54"
		)
		(pin "C57"
		)
		(pin "B64"
		)
		(pin "B65"
		)
		(pin "A58"
		)
		(pin "A59"
		)
		(pin "B92"
		)
		(pin "C43"
		)
		(pin "C45"
		)
		(pin "A97"
		)
		(pin "A11"
		)
		(pin "A61"
		)
		(pin "A62"
		)
		(pin "B48"
		)
		(pin "B54"
		)
		(pin "D71"
		)
		(pin "D72"
		)
		(pin "A26"
		)
		(pin "A36"
		)
		(pin "D31"
		)
		(pin "D36"
		)
		(pin "B76"
		)
		(pin "B21"
		)
		(pin "B24"
		)
		(pin "B94"
		)
		(pin "D3"
		)
		(pin "B79"
		)
		(pin "A85"
		)
		(pin "A23"
		)
		(pin "A25"
		)
		(pin "A24"
		)
		(pin "D14"
		)
		(pin "D18"
		)
		(pin "B15"
		)
		(pin "A107"
		)
		(pin "A98"
		)
		(pin "D9"
		)
		(pin "B44"
		)
		(pin "A4"
		)
		(pin "C28"
		)
		(pin "C31"
		)
		(pin "A9"
		)
		(pin "C49"
		)
		(pin "C50"
		)
		(pin "A83"
		)
		(pin "A110"
		)
		(pin "D52"
		)
		(pin "D53"
		)
		(pin "A40"
		)
		(pin "A71"
		)
		(pin "D98"
		)
		(pin "D99"
		)
		(pin "D40"
		)
		(pin "D42"
		)
		(pin "D37"
		)
		(pin "D41"
		)
		(pin "C109"
		)
		(pin "C11"
		)
		(pin "A106"
		)
		(pin "A3"
		)
		(pin "B109"
		)
		(pin "B40"
		)
		(pin "C70"
		)
		(pin "C73"
		)
		(pin "D13"
		)
		(pin "A1"
		)
		(pin "A46"
		)
		(pin "A20"
		)
		(pin "A104"
		)
		(pin "C9"
		)
		(pin "C110"
		)
		(pin "C14"
		)
		(pin "B23"
		)
		(pin "A93"
		)
		(pin "B89"
		)
		(pin "B87"
		)
		(pin "D54"
		)
		(pin "D60"
		)
		(pin "A21"
		)
		(pin "B93"
		)
		(pin "A70"
		)
		(pin "A60"
		)
		(pin "B97"
		)
		(pin "B95"
		)
		(pin "D38"
		)
		(pin "D39"
		)
		(pin "A50"
		)
		(pin "A52"
		)
		(pin "A53"
		)
		(pin "D91"
		)
		(pin "D92"
		)
		(pin "C67"
		)
		(pin "D57"
		)
		(pin "A96"
		)
		(pin "A92"
		)
		(pin "B70"
		)
		(pin "C46"
		)
		(pin "C47"
		)
		(pin "B4"
		)
		(pin "A64"
		)
		(pin "A65"
		)
		(pin "B43"
		)
		(pin "C21"
		)
		(pin "C25"
		)
		(pin "B42"
		)
		(pin "C19"
		)
		(pin "C20"
		)
		(pin "C18"
		)
		(pin "C2"
		)
		(pin "C107"
		)
		(pin "C108"
		)
		(pin "B35"
		)
		(pin "A28"
		)
		(pin "B11"
		)
		(pin "A103"
		)
		(pin "C97"
		)
		(pin "D1"
		)
		(pin "B98"
		)
		(pin "A19"
		)
		(pin "A68"
		)
		(pin "A69"
		)
		(pin "B55"
		)
		(pin "B56"
		)
		(pin "A8"
		)
		(pin "A33"
		)
		(pin "A95"
		)
		(pin "D96"
		)
		(pin "D97"
		)
		(pin "B31"
		)
		(pin "B105"
		)
		(pin "B100"
		)
		(pin "C65"
		)
		(pin "C66"
		)
		(pin "B104"
		)
		(pin "D61"
		)
		(pin "D62"
		)
		(pin "D78"
		)
		(pin "D79"
		)
		(pin "C83"
		)
		(pin "C84"
		)
		(pin "D74"
		)
		(pin "D75"
		)
		(pin "A45"
		)
		(pin "D106"
		)
		(pin "D107"
		)
		(pin "C8"
		)
		(pin "C80"
		)
		(pin "C87"
		)
		(pin "C90"
		)
		(pin "D58"
		)
		(pin "D59"
		)
		(pin "D104"
		)
		(pin "D105"
		)
		(pin "C93"
		)
		(pin "C96"
		)
		(pin "B73"
		)
		(pin "D108"
		)
		(pin "D109"
		)
		(pin "B20"
		)
		(pin "A27"
		)
		(pin "D34"
		)
		(pin "D35"
		)
		(pin "C17"
		)
		(pin "C24"
		)
		(pin "B49"
		)
		(pin "A6"
		)
		(pin "B5"
		)
		(pin "B99"
		)
		(pin "B25"
		)
		(pin "D94"
		)
		(pin "D95"
		)
		(pin "B106"
		)
		(pin "B67"
		)
		(pin "A2"
		)
		(pin "B13"
		)
		(pin "A49"
		)
		(pin "C52"
		)
		(pin "C53"
		)
		(pin "B72"
		)
		(pin "C94"
		)
		(pin "C95"
		)
		(pin "B74"
		)
		(pin "D10"
		)
		(pin "B75"
		)
		(pin "B77"
		)
		(pin "C98"
		)
		(pin "C99"
		)
		(pin "A7"
		)
		(pin "C88"
		)
		(pin "C89"
		)
		(pin "C10"
		)
		(pin "B78"
		)
		(pin "B81"
		)
		(pin "B28"
		)
		(pin "A63"
		)
		(pin "C76"
		)
		(pin "C77"
		)
		(pin "A55"
		)
		(pin "A56"
		)
		(pin "C48"
		)
		(pin "C5"
		)
		(pin "A5"
		)
		(pin "C1"
		)
		(pin "C100"
		)
		(pin "B47"
		)
		(pin "C74"
		)
		(pin "C75"
		)
		(pin "C12"
		)
		(pin "B80"
		)
		(pin "D15"
		)
		(pin "D16"
		)
		(pin "D100"
		)
		(pin "D103"
		)
		(pin "B2"
		)
		(pin "B9"
		)
		(pin "A94"
		)
		(pin "B82"
		)
		(pin "D25"
		)
		(pin "D28"
		)
		(pin "B16"
		)
		(pin "D65"
		)
		(pin "D66"
		)
		(pin "D32"
		)
		(pin "D33"
		)
		(pin "B8"
		)
		(pin "B60"
		)
		(pin "A38"
		)
		(pin "A73"
		)
		(pin "A80"
		)
		(pin "B18"
		)
		(pin "MP"
		)
		(instances
			(project "com-express-7-baseboard"
				(path ""
					(reference "J12")
					(unit 6)
				)
			)
		)
	)
	(symbol
		(lib_id "antmicroB2BConnectors:Plug_Bus_CE7_EPT_401-51501-51")
		(at 210.82 205.74 0)
		(unit 10)
		(exclude_from_sim no)
		(in_bom yes)
		(on_board yes)
		(dnp no)
		(fields_autoplaced yes)
		(property "Reference" "J12"
			(at 191.77 198.12 0)
			(effects
				(font
					(size 1.27 1.27)
					(thickness 0.15)
				)
			)
		)
		(property "Value" "Plug_Bus_CE7_EPT_401-51501-51"
			(at 264.16 218.44 0)
			(effects
				(font
					(size 1.27 1.27)
					(thickness 0.15)
				)
				(justify left bottom)
				(hide yes)
			)
		)
		(property "Footprint" "antmicro-footprints:EPT_401-51501-51"
			(at 264.16 220.98 0)
			(effects
				(font
					(size 1.27 1.27)
					(thickness 0.15)
				)
				(justify left bottom)
				(hide yes)
			)
		)
		(property "Datasheet" "https://www.farnell.com/datasheets/1905093.pdf"
			(at 264.16 223.52 0)
			(effects
				(font
					(size 1.27 1.27)
					(thickness 0.15)
				)
				(justify left bottom)
				(hide yes)
			)
		)
		(property "Description" ""
			(at 210.82 205.74 0)
			(effects
				(font
					(size 1.27 1.27)
				)
				(hide yes)
			)
		)
		(property "Author" "Antmicro"
			(at 264.16 226.06 0)
			(effects
				(font
					(size 1.27 1.27)
					(thickness 0.15)
				)
				(justify left bottom)
				(hide yes)
			)
		)
		(property "License" "Apache-2.0"
			(at 264.16 228.6 0)
			(effects
				(font
					(size 1.27 1.27)
					(thickness 0.15)
				)
				(justify left bottom)
				(hide yes)
			)
		)
		(property "Manufacturer" "ept"
			(at 264.16 210.82 0)
			(effects
				(font
					(size 1.27 1.27)
					(thickness 0.15)
				)
				(justify left bottom)
				(hide yes)
			)
		)
		(property "MPN" "401-51501-51"
			(at 191.77 200.66 0)
			(effects
				(font
					(size 1.27 1.27)
					(thickness 0.15)
				)
			)
		)
		(pin "C91"
		)
		(pin "C92"
		)
		(pin "A15"
		)
		(pin "A91"
		)
		(pin "C34"
		)
		(pin "C35"
		)
		(pin "D22"
		)
		(pin "D23"
		)
		(pin "D55"
		)
		(pin "D56"
		)
		(pin "C55"
		)
		(pin "C56"
		)
		(pin "C71"
		)
		(pin "C72"
		)
		(pin "C32"
		)
		(pin "C33"
		)
		(pin "B6"
		)
		(pin "B58"
		)
		(pin "B59"
		)
		(pin "D5"
		)
		(pin "D51"
		)
		(pin "A29"
		)
		(pin "D46"
		)
		(pin "D47"
		)
		(pin "C105"
		)
		(pin "C106"
		)
		(pin "A16"
		)
		(pin "B22"
		)
		(pin "B51"
		)
		(pin "B30"
		)
		(pin "A44"
		)
		(pin "C51"
		)
		(pin "C60"
		)
		(pin "A81"
		)
		(pin "A82"
		)
		(pin "D90"
		)
		(pin "D93"
		)
		(pin "B68"
		)
		(pin "B69"
		)
		(pin "C103"
		)
		(pin "C104"
		)
		(pin "C58"
		)
		(pin "C59"
		)
		(pin "D84"
		)
		(pin "D87"
		)
		(pin "A30"
		)
		(pin "B29"
		)
		(pin "A41"
		)
		(pin "C40"
		)
		(pin "C42"
		)
		(pin "D80"
		)
		(pin "D83"
		)
		(pin "B103"
		)
		(pin "A102"
		)
		(pin "C101"
		)
		(pin "C102"
		)
		(pin "D11"
		)
		(pin "D110"
		)
		(pin "B37"
		)
		(pin "B45"
		)
		(pin "C61"
		)
		(pin "C62"
		)
		(pin "A42"
		)
		(pin "B36"
		)
		(pin "B57"
		)
		(pin "D12"
		)
		(pin "D44"
		)
		(pin "D48"
		)
		(pin "B32"
		)
		(pin "B107"
		)
		(pin "B108"
		)
		(pin "B110"
		)
		(pin "B101"
		)
		(pin "C63"
		)
		(pin "C64"
		)
		(pin "B50"
		)
		(pin "A87"
		)
		(pin "A86"
		)
		(pin "B27"
		)
		(pin "D17"
		)
		(pin "D24"
		)
		(pin "D26"
		)
		(pin "D27"
		)
		(pin "A47"
		)
		(pin "C81"
		)
		(pin "C82"
		)
		(pin "C68"
		)
		(pin "C69"
		)
		(pin "A74"
		)
		(pin "A48"
		)
		(pin "A57"
		)
		(pin "A43"
		)
		(pin "A31"
		)
		(pin "D29"
		)
		(pin "D30"
		)
		(pin "C36"
		)
		(pin "C37"
		)
		(pin "C3"
		)
		(pin "A35"
		)
		(pin "A34"
		)
		(pin "B7"
		)
		(pin "B46"
		)
		(pin "B1"
		)
		(pin "B63"
		)
		(pin "A51"
		)
		(pin "A99"
		)
		(pin "B17"
		)
		(pin "C13"
		)
		(pin "C4"
		)
		(pin "B102"
		)
		(pin "C38"
		)
		(pin "C39"
		)
		(pin "B3"
		)
		(pin "A90"
		)
		(pin "A72"
		)
		(pin "B84"
		)
		(pin "D19"
		)
		(pin "D20"
		)
		(pin "D43"
		)
		(pin "D45"
		)
		(pin "A77"
		)
		(pin "A78"
		)
		(pin "B38"
		)
		(pin "B86"
		)
		(pin "D77"
		)
		(pin "D8"
		)
		(pin "A32"
		)
		(pin "B85"
		)
		(pin "D73"
		)
		(pin "D76"
		)
		(pin "D63"
		)
		(pin "D64"
		)
		(pin "D67"
		)
		(pin "D70"
		)
		(pin "B83"
		)
		(pin "D81"
		)
		(pin "D82"
		)
		(pin "B41"
		)
		(pin "D49"
		)
		(pin "D50"
		)
		(pin "A75"
		)
		(pin "D2"
		)
		(pin "D21"
		)
		(pin "C78"
		)
		(pin "C79"
		)
		(pin "B19"
		)
		(pin "B39"
		)
		(pin "A12"
		)
		(pin "B66"
		)
		(pin "D4"
		)
		(pin "D85"
		)
		(pin "D86"
		)
		(pin "A105"
		)
		(pin "B90"
		)
		(pin "A22"
		)
		(pin "A109"
		)
		(pin "B88"
		)
		(pin "B14"
		)
		(pin "B71"
		)
		(pin "B52"
		)
		(pin "B53"
		)
		(pin "D7"
		)
		(pin "A108"
		)
		(pin "C85"
		)
		(pin "C86"
		)
		(pin "B61"
		)
		(pin "B62"
		)
		(pin "D68"
		)
		(pin "D69"
		)
		(pin "A88"
		)
		(pin "A89"
		)
		(pin "D6"
		)
		(pin "C7"
		)
		(pin "B33"
		)
		(pin "D88"
		)
		(pin "D89"
		)
		(pin "B26"
		)
		(pin "A76"
		)
		(pin "D101"
		)
		(pin "D102"
		)
		(pin "B12"
		)
		(pin "C15"
		)
		(pin "C16"
		)
		(pin "A18"
		)
		(pin "A13"
		)
		(pin "A66"
		)
		(pin "C26"
		)
		(pin "C27"
		)
		(pin "A101"
		)
		(pin "A17"
		)
		(pin "B96"
		)
		(pin "C22"
		)
		(pin "C23"
		)
		(pin "A79"
		)
		(pin "A54"
		)
		(pin "C41"
		)
		(pin "C44"
		)
		(pin "A100"
		)
		(pin "A67"
		)
		(pin "A10"
		)
		(pin "A14"
		)
		(pin "C6"
		)
		(pin "A84"
		)
		(pin "B91"
		)
		(pin "C29"
		)
		(pin "C30"
		)
		(pin "A37"
		)
		(pin "A39"
		)
		(pin "B10"
		)
		(pin "B34"
		)
		(pin "C54"
		)
		(pin "C57"
		)
		(pin "B64"
		)
		(pin "B65"
		)
		(pin "A58"
		)
		(pin "A59"
		)
		(pin "B92"
		)
		(pin "C43"
		)
		(pin "C45"
		)
		(pin "A97"
		)
		(pin "A11"
		)
		(pin "A61"
		)
		(pin "A62"
		)
		(pin "B48"
		)
		(pin "B54"
		)
		(pin "D71"
		)
		(pin "D72"
		)
		(pin "A26"
		)
		(pin "A36"
		)
		(pin "D31"
		)
		(pin "D36"
		)
		(pin "B76"
		)
		(pin "B21"
		)
		(pin "B24"
		)
		(pin "B94"
		)
		(pin "D3"
		)
		(pin "B79"
		)
		(pin "A85"
		)
		(pin "A23"
		)
		(pin "A25"
		)
		(pin "A24"
		)
		(pin "D14"
		)
		(pin "D18"
		)
		(pin "B15"
		)
		(pin "A107"
		)
		(pin "A98"
		)
		(pin "D9"
		)
		(pin "B44"
		)
		(pin "A4"
		)
		(pin "C28"
		)
		(pin "C31"
		)
		(pin "A9"
		)
		(pin "C49"
		)
		(pin "C50"
		)
		(pin "A83"
		)
		(pin "A110"
		)
		(pin "D52"
		)
		(pin "D53"
		)
		(pin "A40"
		)
		(pin "A71"
		)
		(pin "D98"
		)
		(pin "D99"
		)
		(pin "D40"
		)
		(pin "D42"
		)
		(pin "D37"
		)
		(pin "D41"
		)
		(pin "C109"
		)
		(pin "C11"
		)
		(pin "A106"
		)
		(pin "A3"
		)
		(pin "B109"
		)
		(pin "B40"
		)
		(pin "C70"
		)
		(pin "C73"
		)
		(pin "D13"
		)
		(pin "A1"
		)
		(pin "A46"
		)
		(pin "A20"
		)
		(pin "A104"
		)
		(pin "C9"
		)
		(pin "C110"
		)
		(pin "C14"
		)
		(pin "B23"
		)
		(pin "A93"
		)
		(pin "B89"
		)
		(pin "B87"
		)
		(pin "D54"
		)
		(pin "D60"
		)
		(pin "A21"
		)
		(pin "B93"
		)
		(pin "A70"
		)
		(pin "A60"
		)
		(pin "B97"
		)
		(pin "B95"
		)
		(pin "D38"
		)
		(pin "D39"
		)
		(pin "A50"
		)
		(pin "A52"
		)
		(pin "A53"
		)
		(pin "D91"
		)
		(pin "D92"
		)
		(pin "C67"
		)
		(pin "D57"
		)
		(pin "A96"
		)
		(pin "A92"
		)
		(pin "B70"
		)
		(pin "C46"
		)
		(pin "C47"
		)
		(pin "B4"
		)
		(pin "A64"
		)
		(pin "A65"
		)
		(pin "B43"
		)
		(pin "C21"
		)
		(pin "C25"
		)
		(pin "B42"
		)
		(pin "C19"
		)
		(pin "C20"
		)
		(pin "C18"
		)
		(pin "C2"
		)
		(pin "C107"
		)
		(pin "C108"
		)
		(pin "B35"
		)
		(pin "A28"
		)
		(pin "B11"
		)
		(pin "A103"
		)
		(pin "C97"
		)
		(pin "D1"
		)
		(pin "B98"
		)
		(pin "A19"
		)
		(pin "A68"
		)
		(pin "A69"
		)
		(pin "B55"
		)
		(pin "B56"
		)
		(pin "A8"
		)
		(pin "A33"
		)
		(pin "A95"
		)
		(pin "D96"
		)
		(pin "D97"
		)
		(pin "B31"
		)
		(pin "B105"
		)
		(pin "B100"
		)
		(pin "C65"
		)
		(pin "C66"
		)
		(pin "B104"
		)
		(pin "D61"
		)
		(pin "D62"
		)
		(pin "D78"
		)
		(pin "D79"
		)
		(pin "C83"
		)
		(pin "C84"
		)
		(pin "D74"
		)
		(pin "D75"
		)
		(pin "A45"
		)
		(pin "D106"
		)
		(pin "D107"
		)
		(pin "C8"
		)
		(pin "C80"
		)
		(pin "C87"
		)
		(pin "C90"
		)
		(pin "D58"
		)
		(pin "D59"
		)
		(pin "D104"
		)
		(pin "D105"
		)
		(pin "C93"
		)
		(pin "C96"
		)
		(pin "B73"
		)
		(pin "D108"
		)
		(pin "D109"
		)
		(pin "B20"
		)
		(pin "A27"
		)
		(pin "D34"
		)
		(pin "D35"
		)
		(pin "C17"
		)
		(pin "C24"
		)
		(pin "B49"
		)
		(pin "A6"
		)
		(pin "B5"
		)
		(pin "B99"
		)
		(pin "B25"
		)
		(pin "D94"
		)
		(pin "D95"
		)
		(pin "B106"
		)
		(pin "B67"
		)
		(pin "A2"
		)
		(pin "B13"
		)
		(pin "A49"
		)
		(pin "C52"
		)
		(pin "C53"
		)
		(pin "B72"
		)
		(pin "C94"
		)
		(pin "C95"
		)
		(pin "B74"
		)
		(pin "D10"
		)
		(pin "B75"
		)
		(pin "B77"
		)
		(pin "C98"
		)
		(pin "C99"
		)
		(pin "A7"
		)
		(pin "C88"
		)
		(pin "C89"
		)
		(pin "C10"
		)
		(pin "B78"
		)
		(pin "B81"
		)
		(pin "B28"
		)
		(pin "A63"
		)
		(pin "C76"
		)
		(pin "C77"
		)
		(pin "A55"
		)
		(pin "A56"
		)
		(pin "C48"
		)
		(pin "C5"
		)
		(pin "A5"
		)
		(pin "C1"
		)
		(pin "C100"
		)
		(pin "B47"
		)
		(pin "C74"
		)
		(pin "C75"
		)
		(pin "C12"
		)
		(pin "B80"
		)
		(pin "D15"
		)
		(pin "D16"
		)
		(pin "D100"
		)
		(pin "D103"
		)
		(pin "B2"
		)
		(pin "B9"
		)
		(pin "A94"
		)
		(pin "B82"
		)
		(pin "D25"
		)
		(pin "D28"
		)
		(pin "B16"
		)
		(pin "D65"
		)
		(pin "D66"
		)
		(pin "D32"
		)
		(pin "D33"
		)
		(pin "B8"
		)
		(pin "B60"
		)
		(pin "A38"
		)
		(pin "A73"
		)
		(pin "A80"
		)
		(pin "B18"
		)
		(pin "MP"
		)
		(instances
			(project "com-express-7-baseboard"
				(path ""
					(reference "J12")
					(unit 10)
				)
			)
		)
	)
	(symbol
		(lib_id "antmicroModules:Mech_SolidRun_LX2160A-CEX7")
		(at 246.38 232.41 0)
		(unit 1)
		(exclude_from_sim no)
		(in_bom no)
		(on_board yes)
		(dnp yes)
		(fields_autoplaced yes)
		(property "Reference" "A3"
			(at 257.81 233.045 0)
			(effects
				(font
					(size 1.27 1.27)
					(thickness 0.15)
				)
				(justify left)
			)
		)
		(property "Value" "Mech_SolidRun_LX2160A-CEX7"
			(at 260.35 236.22 0)
			(effects
				(font
					(size 1.27 1.27)
					(thickness 0.15)
				)
				(justify left bottom)
				(hide yes)
			)
		)
		(property "Footprint" "antmicro-footprints:Mech_SolidRun_LX2160A-CEX7"
			(at 260.35 238.76 0)
			(effects
				(font
					(size 1.27 1.27)
					(thickness 0.15)
				)
				(justify left bottom)
				(hide yes)
			)
		)
		(property "Datasheet" "https://www.solid-run.com/embedded-networking/nxp-lx2160a-family/cex7-lx2160/#documentation"
			(at 260.35 241.3 0)
			(effects
				(font
					(size 1.27 1.27)
					(thickness 0.15)
				)
				(justify left bottom)
				(hide yes)
			)
		)
		(property "Description" ""
			(at 246.38 232.41 0)
			(effects
				(font
					(size 1.27 1.27)
				)
				(hide yes)
			)
		)
		(property "MPN" "SRX2160S01D00GE064V21C0"
			(at 257.81 235.585 0)
			(effects
				(font
					(size 1.27 1.27)
					(thickness 0.15)
				)
				(justify left)
			)
		)
		(property "Manufacturer" "SolidRun"
			(at 260.35 246.38 0)
			(effects
				(font
					(size 1.27 1.27)
					(thickness 0.15)
				)
				(justify left bottom)
				(hide yes)
			)
		)
		(property "Author" "Antmicro"
			(at 260.35 248.92 0)
			(effects
				(font
					(size 1.27 1.27)
					(thickness 0.15)
				)
				(justify left bottom)
				(hide yes)
			)
		)
		(property "License" "Apache-2.0"
			(at 260.35 251.46 0)
			(effects
				(font
					(size 1.27 1.27)
					(thickness 0.15)
				)
				(justify left bottom)
				(hide yes)
			)
		)
		(property "Displayed name" "LX2160A-CEX7"
			(at 257.81 238.125 0)
			(effects
				(font
					(size 1.27 1.27)
				)
				(justify left)
			)
		)
		(instances
			(project "com-express-7-baseboard"
				(path ""
					(reference "A3")
					(unit 1)
				)
			)
		)
	)
	(symbol
		(lib_id "antmicroResistors0402:R_10k_0402")
		(at 369.57 100.33 90)
		(unit 1)
		(exclude_from_sim no)
		(in_bom yes)
		(on_board yes)
		(dnp no)
		(fields_autoplaced yes)
		(property "Reference" "R158"
			(at 372.11 96.52 90)
			(effects
				(font
					(size 1.27 1.27)
					(thickness 0.15)
				)
				(justify right)
			)
		)
		(property "Value" "R_10k_0402"
			(at 382.27 80.01 0)
			(effects
				(font
					(size 1.27 1.27)
					(thickness 0.15)
				)
				(justify left bottom)
				(hide yes)
			)
		)
		(property "Footprint" "antmicro-footprints:R_0402_1005Metric"
			(at 384.81 80.01 0)
			(effects
				(font
					(size 1.27 1.27)
					(thickness 0.15)
				)
				(justify left bottom)
				(hide yes)
			)
		)
		(property "Datasheet" "https://www.bourns.com/docs/product-datasheets/cr.pdf"
			(at 387.35 80.01 0)
			(effects
				(font
					(size 1.27 1.27)
					(thickness 0.15)
				)
				(justify left bottom)
				(hide yes)
			)
		)
		(property "Description" ""
			(at 369.57 100.33 0)
			(effects
				(font
					(size 1.27 1.27)
				)
				(hide yes)
			)
		)
		(property "MPN" "CR0402-FX-1002GLF"
			(at 389.89 80.01 0)
			(effects
				(font
					(size 1.27 1.27)
					(thickness 0.15)
				)
				(justify left bottom)
				(hide yes)
			)
		)
		(property "Manufacturer" "Bourns"
			(at 392.43 80.01 0)
			(effects
				(font
					(size 1.27 1.27)
					(thickness 0.15)
				)
				(justify left bottom)
				(hide yes)
			)
		)
		(property "License" "Apache-2.0"
			(at 394.97 80.01 0)
			(effects
				(font
					(size 1.27 1.27)
					(thickness 0.15)
				)
				(justify left bottom)
				(hide yes)
			)
		)
		(property "Author" "Antmicro"
			(at 397.51 80.01 0)
			(effects
				(font
					(size 1.27 1.27)
					(thickness 0.15)
				)
				(justify left bottom)
				(hide yes)
			)
		)
		(property "Val" "10k"
			(at 372.11 99.06 90)
			(effects
				(font
					(size 1.27 1.27)
					(thickness 0.15)
				)
				(justify right)
			)
		)
		(property "Tolerance" "1%"
			(at 379.73 80.01 0)
			(effects
				(font
					(size 1.27 1.27)
				)
				(justify left bottom)
				(hide yes)
			)
		)
		(property "Public" "False"
			(at 400.05 80.01 0)
			(effects
				(font
					(size 1.27 1.27)
				)
				(justify left bottom)
				(hide yes)
			)
		)
		(pin "2"
		)
		(pin "1"
		)
		(instances
			(project "com-express-7-baseboard"
				(path ""
					(reference "R158")
					(unit 1)
				)
			)
		)
	)
	(symbol
		(lib_id "antmicroB2BConnectors:Plug_Bus_CE7_EPT_401-51501-51")
		(at 355.6 76.2 0)
		(unit 5)
		(exclude_from_sim no)
		(in_bom yes)
		(on_board yes)
		(dnp no)
		(fields_autoplaced yes)
		(property "Reference" "J12"
			(at 336.55 68.58 0)
			(effects
				(font
					(size 1.27 1.27)
					(thickness 0.15)
				)
			)
		)
		(property "Value" "Plug_Bus_CE7_EPT_401-51501-51"
			(at 408.94 88.9 0)
			(effects
				(font
					(size 1.27 1.27)
					(thickness 0.15)
				)
				(justify left bottom)
				(hide yes)
			)
		)
		(property "Footprint" "antmicro-footprints:EPT_401-51501-51"
			(at 408.94 91.44 0)
			(effects
				(font
					(size 1.27 1.27)
					(thickness 0.15)
				)
				(justify left bottom)
				(hide yes)
			)
		)
		(property "Datasheet" "https://www.farnell.com/datasheets/1905093.pdf"
			(at 408.94 93.98 0)
			(effects
				(font
					(size 1.27 1.27)
					(thickness 0.15)
				)
				(justify left bottom)
				(hide yes)
			)
		)
		(property "Description" ""
			(at 355.6 76.2 0)
			(effects
				(font
					(size 1.27 1.27)
				)
				(hide yes)
			)
		)
		(property "Author" "Antmicro"
			(at 408.94 96.52 0)
			(effects
				(font
					(size 1.27 1.27)
					(thickness 0.15)
				)
				(justify left bottom)
				(hide yes)
			)
		)
		(property "License" "Apache-2.0"
			(at 408.94 99.06 0)
			(effects
				(font
					(size 1.27 1.27)
					(thickness 0.15)
				)
				(justify left bottom)
				(hide yes)
			)
		)
		(property "Manufacturer" "ept"
			(at 408.94 81.28 0)
			(effects
				(font
					(size 1.27 1.27)
					(thickness 0.15)
				)
				(justify left bottom)
				(hide yes)
			)
		)
		(property "MPN" "401-51501-51"
			(at 336.55 71.12 0)
			(effects
				(font
					(size 1.27 1.27)
					(thickness 0.15)
				)
			)
		)
		(pin "C91"
		)
		(pin "C92"
		)
		(pin "A15"
		)
		(pin "A91"
		)
		(pin "C34"
		)
		(pin "C35"
		)
		(pin "D22"
		)
		(pin "D23"
		)
		(pin "D55"
		)
		(pin "D56"
		)
		(pin "C55"
		)
		(pin "C56"
		)
		(pin "C71"
		)
		(pin "C72"
		)
		(pin "C32"
		)
		(pin "C33"
		)
		(pin "B6"
		)
		(pin "B58"
		)
		(pin "B59"
		)
		(pin "D5"
		)
		(pin "D51"
		)
		(pin "A29"
		)
		(pin "D46"
		)
		(pin "D47"
		)
		(pin "C105"
		)
		(pin "C106"
		)
		(pin "A16"
		)
		(pin "B22"
		)
		(pin "B51"
		)
		(pin "B30"
		)
		(pin "A44"
		)
		(pin "C51"
		)
		(pin "C60"
		)
		(pin "A81"
		)
		(pin "A82"
		)
		(pin "D90"
		)
		(pin "D93"
		)
		(pin "B68"
		)
		(pin "B69"
		)
		(pin "C103"
		)
		(pin "C104"
		)
		(pin "C58"
		)
		(pin "C59"
		)
		(pin "D84"
		)
		(pin "D87"
		)
		(pin "A30"
		)
		(pin "B29"
		)
		(pin "A41"
		)
		(pin "C40"
		)
		(pin "C42"
		)
		(pin "D80"
		)
		(pin "D83"
		)
		(pin "B103"
		)
		(pin "A102"
		)
		(pin "C101"
		)
		(pin "C102"
		)
		(pin "D11"
		)
		(pin "D110"
		)
		(pin "B37"
		)
		(pin "B45"
		)
		(pin "C61"
		)
		(pin "C62"
		)
		(pin "A42"
		)
		(pin "B36"
		)
		(pin "B57"
		)
		(pin "D12"
		)
		(pin "D44"
		)
		(pin "D48"
		)
		(pin "B32"
		)
		(pin "B107"
		)
		(pin "B108"
		)
		(pin "B110"
		)
		(pin "B101"
		)
		(pin "C63"
		)
		(pin "C64"
		)
		(pin "B50"
		)
		(pin "A87"
		)
		(pin "A86"
		)
		(pin "B27"
		)
		(pin "D17"
		)
		(pin "D24"
		)
		(pin "D26"
		)
		(pin "D27"
		)
		(pin "A47"
		)
		(pin "C81"
		)
		(pin "C82"
		)
		(pin "C68"
		)
		(pin "C69"
		)
		(pin "A74"
		)
		(pin "A48"
		)
		(pin "A57"
		)
		(pin "A43"
		)
		(pin "A31"
		)
		(pin "D29"
		)
		(pin "D30"
		)
		(pin "C36"
		)
		(pin "C37"
		)
		(pin "C3"
		)
		(pin "A35"
		)
		(pin "A34"
		)
		(pin "B7"
		)
		(pin "B46"
		)
		(pin "B1"
		)
		(pin "B63"
		)
		(pin "A51"
		)
		(pin "A99"
		)
		(pin "B17"
		)
		(pin "C13"
		)
		(pin "C4"
		)
		(pin "B102"
		)
		(pin "C38"
		)
		(pin "C39"
		)
		(pin "B3"
		)
		(pin "A90"
		)
		(pin "A72"
		)
		(pin "B84"
		)
		(pin "D19"
		)
		(pin "D20"
		)
		(pin "D43"
		)
		(pin "D45"
		)
		(pin "A77"
		)
		(pin "A78"
		)
		(pin "B38"
		)
		(pin "B86"
		)
		(pin "D77"
		)
		(pin "D8"
		)
		(pin "A32"
		)
		(pin "B85"
		)
		(pin "D73"
		)
		(pin "D76"
		)
		(pin "D63"
		)
		(pin "D64"
		)
		(pin "D67"
		)
		(pin "D70"
		)
		(pin "B83"
		)
		(pin "D81"
		)
		(pin "D82"
		)
		(pin "B41"
		)
		(pin "D49"
		)
		(pin "D50"
		)
		(pin "A75"
		)
		(pin "D2"
		)
		(pin "D21"
		)
		(pin "C78"
		)
		(pin "C79"
		)
		(pin "B19"
		)
		(pin "B39"
		)
		(pin "A12"
		)
		(pin "B66"
		)
		(pin "D4"
		)
		(pin "D85"
		)
		(pin "D86"
		)
		(pin "A105"
		)
		(pin "B90"
		)
		(pin "A22"
		)
		(pin "A109"
		)
		(pin "B88"
		)
		(pin "B14"
		)
		(pin "B71"
		)
		(pin "B52"
		)
		(pin "B53"
		)
		(pin "D7"
		)
		(pin "A108"
		)
		(pin "C85"
		)
		(pin "C86"
		)
		(pin "B61"
		)
		(pin "B62"
		)
		(pin "D68"
		)
		(pin "D69"
		)
		(pin "A88"
		)
		(pin "A89"
		)
		(pin "D6"
		)
		(pin "C7"
		)
		(pin "B33"
		)
		(pin "D88"
		)
		(pin "D89"
		)
		(pin "B26"
		)
		(pin "A76"
		)
		(pin "D101"
		)
		(pin "D102"
		)
		(pin "B12"
		)
		(pin "C15"
		)
		(pin "C16"
		)
		(pin "A18"
		)
		(pin "A13"
		)
		(pin "A66"
		)
		(pin "C26"
		)
		(pin "C27"
		)
		(pin "A101"
		)
		(pin "A17"
		)
		(pin "B96"
		)
		(pin "C22"
		)
		(pin "C23"
		)
		(pin "A79"
		)
		(pin "A54"
		)
		(pin "C41"
		)
		(pin "C44"
		)
		(pin "A100"
		)
		(pin "A67"
		)
		(pin "A10"
		)
		(pin "A14"
		)
		(pin "C6"
		)
		(pin "A84"
		)
		(pin "B91"
		)
		(pin "C29"
		)
		(pin "C30"
		)
		(pin "A37"
		)
		(pin "A39"
		)
		(pin "B10"
		)
		(pin "B34"
		)
		(pin "C54"
		)
		(pin "C57"
		)
		(pin "B64"
		)
		(pin "B65"
		)
		(pin "A58"
		)
		(pin "A59"
		)
		(pin "B92"
		)
		(pin "C43"
		)
		(pin "C45"
		)
		(pin "A97"
		)
		(pin "A11"
		)
		(pin "A61"
		)
		(pin "A62"
		)
		(pin "B48"
		)
		(pin "B54"
		)
		(pin "D71"
		)
		(pin "D72"
		)
		(pin "A26"
		)
		(pin "A36"
		)
		(pin "D31"
		)
		(pin "D36"
		)
		(pin "B76"
		)
		(pin "B21"
		)
		(pin "B24"
		)
		(pin "B94"
		)
		(pin "D3"
		)
		(pin "B79"
		)
		(pin "A85"
		)
		(pin "A23"
		)
		(pin "A25"
		)
		(pin "A24"
		)
		(pin "D14"
		)
		(pin "D18"
		)
		(pin "B15"
		)
		(pin "A107"
		)
		(pin "A98"
		)
		(pin "D9"
		)
		(pin "B44"
		)
		(pin "A4"
		)
		(pin "C28"
		)
		(pin "C31"
		)
		(pin "A9"
		)
		(pin "C49"
		)
		(pin "C50"
		)
		(pin "A83"
		)
		(pin "A110"
		)
		(pin "D52"
		)
		(pin "D53"
		)
		(pin "A40"
		)
		(pin "A71"
		)
		(pin "D98"
		)
		(pin "D99"
		)
		(pin "D40"
		)
		(pin "D42"
		)
		(pin "D37"
		)
		(pin "D41"
		)
		(pin "C109"
		)
		(pin "C11"
		)
		(pin "A106"
		)
		(pin "A3"
		)
		(pin "B109"
		)
		(pin "B40"
		)
		(pin "C70"
		)
		(pin "C73"
		)
		(pin "D13"
		)
		(pin "A1"
		)
		(pin "A46"
		)
		(pin "A20"
		)
		(pin "A104"
		)
		(pin "C9"
		)
		(pin "C110"
		)
		(pin "C14"
		)
		(pin "B23"
		)
		(pin "A93"
		)
		(pin "B89"
		)
		(pin "B87"
		)
		(pin "D54"
		)
		(pin "D60"
		)
		(pin "A21"
		)
		(pin "B93"
		)
		(pin "A70"
		)
		(pin "A60"
		)
		(pin "B97"
		)
		(pin "B95"
		)
		(pin "D38"
		)
		(pin "D39"
		)
		(pin "A50"
		)
		(pin "A52"
		)
		(pin "A53"
		)
		(pin "D91"
		)
		(pin "D92"
		)
		(pin "C67"
		)
		(pin "D57"
		)
		(pin "A96"
		)
		(pin "A92"
		)
		(pin "B70"
		)
		(pin "C46"
		)
		(pin "C47"
		)
		(pin "B4"
		)
		(pin "A64"
		)
		(pin "A65"
		)
		(pin "B43"
		)
		(pin "C21"
		)
		(pin "C25"
		)
		(pin "B42"
		)
		(pin "C19"
		)
		(pin "C20"
		)
		(pin "C18"
		)
		(pin "C2"
		)
		(pin "C107"
		)
		(pin "C108"
		)
		(pin "B35"
		)
		(pin "A28"
		)
		(pin "B11"
		)
		(pin "A103"
		)
		(pin "C97"
		)
		(pin "D1"
		)
		(pin "B98"
		)
		(pin "A19"
		)
		(pin "A68"
		)
		(pin "A69"
		)
		(pin "B55"
		)
		(pin "B56"
		)
		(pin "A8"
		)
		(pin "A33"
		)
		(pin "A95"
		)
		(pin "D96"
		)
		(pin "D97"
		)
		(pin "B31"
		)
		(pin "B105"
		)
		(pin "B100"
		)
		(pin "C65"
		)
		(pin "C66"
		)
		(pin "B104"
		)
		(pin "D61"
		)
		(pin "D62"
		)
		(pin "D78"
		)
		(pin "D79"
		)
		(pin "C83"
		)
		(pin "C84"
		)
		(pin "D74"
		)
		(pin "D75"
		)
		(pin "A45"
		)
		(pin "D106"
		)
		(pin "D107"
		)
		(pin "C8"
		)
		(pin "C80"
		)
		(pin "C87"
		)
		(pin "C90"
		)
		(pin "D58"
		)
		(pin "D59"
		)
		(pin "D104"
		)
		(pin "D105"
		)
		(pin "C93"
		)
		(pin "C96"
		)
		(pin "B73"
		)
		(pin "D108"
		)
		(pin "D109"
		)
		(pin "B20"
		)
		(pin "A27"
		)
		(pin "D34"
		)
		(pin "D35"
		)
		(pin "C17"
		)
		(pin "C24"
		)
		(pin "B49"
		)
		(pin "A6"
		)
		(pin "B5"
		)
		(pin "B99"
		)
		(pin "B25"
		)
		(pin "D94"
		)
		(pin "D95"
		)
		(pin "B106"
		)
		(pin "B67"
		)
		(pin "A2"
		)
		(pin "B13"
		)
		(pin "A49"
		)
		(pin "C52"
		)
		(pin "C53"
		)
		(pin "B72"
		)
		(pin "C94"
		)
		(pin "C95"
		)
		(pin "B74"
		)
		(pin "D10"
		)
		(pin "B75"
		)
		(pin "B77"
		)
		(pin "C98"
		)
		(pin "C99"
		)
		(pin "A7"
		)
		(pin "C88"
		)
		(pin "C89"
		)
		(pin "C10"
		)
		(pin "B78"
		)
		(pin "B81"
		)
		(pin "B28"
		)
		(pin "A63"
		)
		(pin "C76"
		)
		(pin "C77"
		)
		(pin "A55"
		)
		(pin "A56"
		)
		(pin "C48"
		)
		(pin "C5"
		)
		(pin "A5"
		)
		(pin "C1"
		)
		(pin "C100"
		)
		(pin "B47"
		)
		(pin "C74"
		)
		(pin "C75"
		)
		(pin "C12"
		)
		(pin "B80"
		)
		(pin "D15"
		)
		(pin "D16"
		)
		(pin "D100"
		)
		(pin "D103"
		)
		(pin "B2"
		)
		(pin "B9"
		)
		(pin "A94"
		)
		(pin "B82"
		)
		(pin "D25"
		)
		(pin "D28"
		)
		(pin "B16"
		)
		(pin "D65"
		)
		(pin "D66"
		)
		(pin "D32"
		)
		(pin "D33"
		)
		(pin "B8"
		)
		(pin "B60"
		)
		(pin "A38"
		)
		(pin "A73"
		)
		(pin "A80"
		)
		(pin "B18"
		)
		(pin "MP"
		)
		(instances
			(project "com-express-7-baseboard"
				(path ""
					(reference "J12")
					(unit 5)
				)
			)
		)
	)
	(symbol
		(lib_id "antmicroB2BConnectors:Plug_Bus_CE7_EPT_401-51501-51")
		(at 210.82 157.48 0)
		(unit 7)
		(exclude_from_sim no)
		(in_bom yes)
		(on_board yes)
		(dnp no)
		(fields_autoplaced yes)
		(property "Reference" "J12"
			(at 191.77 149.86 0)
			(effects
				(font
					(size 1.27 1.27)
					(thickness 0.15)
				)
			)
		)
		(property "Value" "Plug_Bus_CE7_EPT_401-51501-51"
			(at 264.16 170.18 0)
			(effects
				(font
					(size 1.27 1.27)
					(thickness 0.15)
				)
				(justify left bottom)
				(hide yes)
			)
		)
		(property "Footprint" "antmicro-footprints:EPT_401-51501-51"
			(at 264.16 172.72 0)
			(effects
				(font
					(size 1.27 1.27)
					(thickness 0.15)
				)
				(justify left bottom)
				(hide yes)
			)
		)
		(property "Datasheet" "https://www.farnell.com/datasheets/1905093.pdf"
			(at 264.16 175.26 0)
			(effects
				(font
					(size 1.27 1.27)
					(thickness 0.15)
				)
				(justify left bottom)
				(hide yes)
			)
		)
		(property "Description" ""
			(at 210.82 157.48 0)
			(effects
				(font
					(size 1.27 1.27)
				)
				(hide yes)
			)
		)
		(property "Author" "Antmicro"
			(at 264.16 177.8 0)
			(effects
				(font
					(size 1.27 1.27)
					(thickness 0.15)
				)
				(justify left bottom)
				(hide yes)
			)
		)
		(property "License" "Apache-2.0"
			(at 264.16 180.34 0)
			(effects
				(font
					(size 1.27 1.27)
					(thickness 0.15)
				)
				(justify left bottom)
				(hide yes)
			)
		)
		(property "Manufacturer" "ept"
			(at 264.16 162.56 0)
			(effects
				(font
					(size 1.27 1.27)
					(thickness 0.15)
				)
				(justify left bottom)
				(hide yes)
			)
		)
		(property "MPN" "401-51501-51"
			(at 191.77 152.4 0)
			(effects
				(font
					(size 1.27 1.27)
					(thickness 0.15)
				)
			)
		)
		(pin "C91"
		)
		(pin "C92"
		)
		(pin "A15"
		)
		(pin "A91"
		)
		(pin "C34"
		)
		(pin "C35"
		)
		(pin "D22"
		)
		(pin "D23"
		)
		(pin "D55"
		)
		(pin "D56"
		)
		(pin "C55"
		)
		(pin "C56"
		)
		(pin "C71"
		)
		(pin "C72"
		)
		(pin "C32"
		)
		(pin "C33"
		)
		(pin "B6"
		)
		(pin "B58"
		)
		(pin "B59"
		)
		(pin "D5"
		)
		(pin "D51"
		)
		(pin "A29"
		)
		(pin "D46"
		)
		(pin "D47"
		)
		(pin "C105"
		)
		(pin "C106"
		)
		(pin "A16"
		)
		(pin "B22"
		)
		(pin "B51"
		)
		(pin "B30"
		)
		(pin "A44"
		)
		(pin "C51"
		)
		(pin "C60"
		)
		(pin "A81"
		)
		(pin "A82"
		)
		(pin "D90"
		)
		(pin "D93"
		)
		(pin "B68"
		)
		(pin "B69"
		)
		(pin "C103"
		)
		(pin "C104"
		)
		(pin "C58"
		)
		(pin "C59"
		)
		(pin "D84"
		)
		(pin "D87"
		)
		(pin "A30"
		)
		(pin "B29"
		)
		(pin "A41"
		)
		(pin "C40"
		)
		(pin "C42"
		)
		(pin "D80"
		)
		(pin "D83"
		)
		(pin "B103"
		)
		(pin "A102"
		)
		(pin "C101"
		)
		(pin "C102"
		)
		(pin "D11"
		)
		(pin "D110"
		)
		(pin "B37"
		)
		(pin "B45"
		)
		(pin "C61"
		)
		(pin "C62"
		)
		(pin "A42"
		)
		(pin "B36"
		)
		(pin "B57"
		)
		(pin "D12"
		)
		(pin "D44"
		)
		(pin "D48"
		)
		(pin "B32"
		)
		(pin "B107"
		)
		(pin "B108"
		)
		(pin "B110"
		)
		(pin "B101"
		)
		(pin "C63"
		)
		(pin "C64"
		)
		(pin "B50"
		)
		(pin "A87"
		)
		(pin "A86"
		)
		(pin "B27"
		)
		(pin "D17"
		)
		(pin "D24"
		)
		(pin "D26"
		)
		(pin "D27"
		)
		(pin "A47"
		)
		(pin "C81"
		)
		(pin "C82"
		)
		(pin "C68"
		)
		(pin "C69"
		)
		(pin "A74"
		)
		(pin "A48"
		)
		(pin "A57"
		)
		(pin "A43"
		)
		(pin "A31"
		)
		(pin "D29"
		)
		(pin "D30"
		)
		(pin "C36"
		)
		(pin "C37"
		)
		(pin "C3"
		)
		(pin "A35"
		)
		(pin "A34"
		)
		(pin "B7"
		)
		(pin "B46"
		)
		(pin "B1"
		)
		(pin "B63"
		)
		(pin "A51"
		)
		(pin "A99"
		)
		(pin "B17"
		)
		(pin "C13"
		)
		(pin "C4"
		)
		(pin "B102"
		)
		(pin "C38"
		)
		(pin "C39"
		)
		(pin "B3"
		)
		(pin "A90"
		)
		(pin "A72"
		)
		(pin "B84"
		)
		(pin "D19"
		)
		(pin "D20"
		)
		(pin "D43"
		)
		(pin "D45"
		)
		(pin "A77"
		)
		(pin "A78"
		)
		(pin "B38"
		)
		(pin "B86"
		)
		(pin "D77"
		)
		(pin "D8"
		)
		(pin "A32"
		)
		(pin "B85"
		)
		(pin "D73"
		)
		(pin "D76"
		)
		(pin "D63"
		)
		(pin "D64"
		)
		(pin "D67"
		)
		(pin "D70"
		)
		(pin "B83"
		)
		(pin "D81"
		)
		(pin "D82"
		)
		(pin "B41"
		)
		(pin "D49"
		)
		(pin "D50"
		)
		(pin "A75"
		)
		(pin "D2"
		)
		(pin "D21"
		)
		(pin "C78"
		)
		(pin "C79"
		)
		(pin "B19"
		)
		(pin "B39"
		)
		(pin "A12"
		)
		(pin "B66"
		)
		(pin "D4"
		)
		(pin "D85"
		)
		(pin "D86"
		)
		(pin "A105"
		)
		(pin "B90"
		)
		(pin "A22"
		)
		(pin "A109"
		)
		(pin "B88"
		)
		(pin "B14"
		)
		(pin "B71"
		)
		(pin "B52"
		)
		(pin "B53"
		)
		(pin "D7"
		)
		(pin "A108"
		)
		(pin "C85"
		)
		(pin "C86"
		)
		(pin "B61"
		)
		(pin "B62"
		)
		(pin "D68"
		)
		(pin "D69"
		)
		(pin "A88"
		)
		(pin "A89"
		)
		(pin "D6"
		)
		(pin "C7"
		)
		(pin "B33"
		)
		(pin "D88"
		)
		(pin "D89"
		)
		(pin "B26"
		)
		(pin "A76"
		)
		(pin "D101"
		)
		(pin "D102"
		)
		(pin "B12"
		)
		(pin "C15"
		)
		(pin "C16"
		)
		(pin "A18"
		)
		(pin "A13"
		)
		(pin "A66"
		)
		(pin "C26"
		)
		(pin "C27"
		)
		(pin "A101"
		)
		(pin "A17"
		)
		(pin "B96"
		)
		(pin "C22"
		)
		(pin "C23"
		)
		(pin "A79"
		)
		(pin "A54"
		)
		(pin "C41"
		)
		(pin "C44"
		)
		(pin "A100"
		)
		(pin "A67"
		)
		(pin "A10"
		)
		(pin "A14"
		)
		(pin "C6"
		)
		(pin "A84"
		)
		(pin "B91"
		)
		(pin "C29"
		)
		(pin "C30"
		)
		(pin "A37"
		)
		(pin "A39"
		)
		(pin "B10"
		)
		(pin "B34"
		)
		(pin "C54"
		)
		(pin "C57"
		)
		(pin "B64"
		)
		(pin "B65"
		)
		(pin "A58"
		)
		(pin "A59"
		)
		(pin "B92"
		)
		(pin "C43"
		)
		(pin "C45"
		)
		(pin "A97"
		)
		(pin "A11"
		)
		(pin "A61"
		)
		(pin "A62"
		)
		(pin "B48"
		)
		(pin "B54"
		)
		(pin "D71"
		)
		(pin "D72"
		)
		(pin "A26"
		)
		(pin "A36"
		)
		(pin "D31"
		)
		(pin "D36"
		)
		(pin "B76"
		)
		(pin "B21"
		)
		(pin "B24"
		)
		(pin "B94"
		)
		(pin "D3"
		)
		(pin "B79"
		)
		(pin "A85"
		)
		(pin "A23"
		)
		(pin "A25"
		)
		(pin "A24"
		)
		(pin "D14"
		)
		(pin "D18"
		)
		(pin "B15"
		)
		(pin "A107"
		)
		(pin "A98"
		)
		(pin "D9"
		)
		(pin "B44"
		)
		(pin "A4"
		)
		(pin "C28"
		)
		(pin "C31"
		)
		(pin "A9"
		)
		(pin "C49"
		)
		(pin "C50"
		)
		(pin "A83"
		)
		(pin "A110"
		)
		(pin "D52"
		)
		(pin "D53"
		)
		(pin "A40"
		)
		(pin "A71"
		)
		(pin "D98"
		)
		(pin "D99"
		)
		(pin "D40"
		)
		(pin "D42"
		)
		(pin "D37"
		)
		(pin "D41"
		)
		(pin "C109"
		)
		(pin "C11"
		)
		(pin "A106"
		)
		(pin "A3"
		)
		(pin "B109"
		)
		(pin "B40"
		)
		(pin "C70"
		)
		(pin "C73"
		)
		(pin "D13"
		)
		(pin "A1"
		)
		(pin "A46"
		)
		(pin "A20"
		)
		(pin "A104"
		)
		(pin "C9"
		)
		(pin "C110"
		)
		(pin "C14"
		)
		(pin "B23"
		)
		(pin "A93"
		)
		(pin "B89"
		)
		(pin "B87"
		)
		(pin "D54"
		)
		(pin "D60"
		)
		(pin "A21"
		)
		(pin "B93"
		)
		(pin "A70"
		)
		(pin "A60"
		)
		(pin "B97"
		)
		(pin "B95"
		)
		(pin "D38"
		)
		(pin "D39"
		)
		(pin "A50"
		)
		(pin "A52"
		)
		(pin "A53"
		)
		(pin "D91"
		)
		(pin "D92"
		)
		(pin "C67"
		)
		(pin "D57"
		)
		(pin "A96"
		)
		(pin "A92"
		)
		(pin "B70"
		)
		(pin "C46"
		)
		(pin "C47"
		)
		(pin "B4"
		)
		(pin "A64"
		)
		(pin "A65"
		)
		(pin "B43"
		)
		(pin "C21"
		)
		(pin "C25"
		)
		(pin "B42"
		)
		(pin "C19"
		)
		(pin "C20"
		)
		(pin "C18"
		)
		(pin "C2"
		)
		(pin "C107"
		)
		(pin "C108"
		)
		(pin "B35"
		)
		(pin "A28"
		)
		(pin "B11"
		)
		(pin "A103"
		)
		(pin "C97"
		)
		(pin "D1"
		)
		(pin "B98"
		)
		(pin "A19"
		)
		(pin "A68"
		)
		(pin "A69"
		)
		(pin "B55"
		)
		(pin "B56"
		)
		(pin "A8"
		)
		(pin "A33"
		)
		(pin "A95"
		)
		(pin "D96"
		)
		(pin "D97"
		)
		(pin "B31"
		)
		(pin "B105"
		)
		(pin "B100"
		)
		(pin "C65"
		)
		(pin "C66"
		)
		(pin "B104"
		)
		(pin "D61"
		)
		(pin "D62"
		)
		(pin "D78"
		)
		(pin "D79"
		)
		(pin "C83"
		)
		(pin "C84"
		)
		(pin "D74"
		)
		(pin "D75"
		)
		(pin "A45"
		)
		(pin "D106"
		)
		(pin "D107"
		)
		(pin "C8"
		)
		(pin "C80"
		)
		(pin "C87"
		)
		(pin "C90"
		)
		(pin "D58"
		)
		(pin "D59"
		)
		(pin "D104"
		)
		(pin "D105"
		)
		(pin "C93"
		)
		(pin "C96"
		)
		(pin "B73"
		)
		(pin "D108"
		)
		(pin "D109"
		)
		(pin "B20"
		)
		(pin "A27"
		)
		(pin "D34"
		)
		(pin "D35"
		)
		(pin "C17"
		)
		(pin "C24"
		)
		(pin "B49"
		)
		(pin "A6"
		)
		(pin "B5"
		)
		(pin "B99"
		)
		(pin "B25"
		)
		(pin "D94"
		)
		(pin "D95"
		)
		(pin "B106"
		)
		(pin "B67"
		)
		(pin "A2"
		)
		(pin "B13"
		)
		(pin "A49"
		)
		(pin "C52"
		)
		(pin "C53"
		)
		(pin "B72"
		)
		(pin "C94"
		)
		(pin "C95"
		)
		(pin "B74"
		)
		(pin "D10"
		)
		(pin "B75"
		)
		(pin "B77"
		)
		(pin "C98"
		)
		(pin "C99"
		)
		(pin "A7"
		)
		(pin "C88"
		)
		(pin "C89"
		)
		(pin "C10"
		)
		(pin "B78"
		)
		(pin "B81"
		)
		(pin "B28"
		)
		(pin "A63"
		)
		(pin "C76"
		)
		(pin "C77"
		)
		(pin "A55"
		)
		(pin "A56"
		)
		(pin "C48"
		)
		(pin "C5"
		)
		(pin "A5"
		)
		(pin "C1"
		)
		(pin "C100"
		)
		(pin "B47"
		)
		(pin "C74"
		)
		(pin "C75"
		)
		(pin "C12"
		)
		(pin "B80"
		)
		(pin "D15"
		)
		(pin "D16"
		)
		(pin "D100"
		)
		(pin "D103"
		)
		(pin "B2"
		)
		(pin "B9"
		)
		(pin "A94"
		)
		(pin "B82"
		)
		(pin "D25"
		)
		(pin "D28"
		)
		(pin "B16"
		)
		(pin "D65"
		)
		(pin "D66"
		)
		(pin "D32"
		)
		(pin "D33"
		)
		(pin "B8"
		)
		(pin "B60"
		)
		(pin "A38"
		)
		(pin "A73"
		)
		(pin "A80"
		)
		(pin "B18"
		)
		(pin "MP"
		)
		(instances
			(project "com-express-7-baseboard"
				(path ""
					(reference "J12")
					(unit 7)
				)
			)
		)
	)
	(symbol
		(lib_id "antmicroTestPoints:TP_0.75mm_SMD")
		(at 281.94 172.72 0)
		(unit 1)
		(exclude_from_sim no)
		(in_bom no)
		(on_board yes)
		(dnp no)
		(fields_autoplaced yes)
		(property "Reference" "TP19"
			(at 287.02 172.72 0)
			(effects
				(font
					(size 1.27 1.27)
					(thickness 0.15)
				)
				(justify left)
			)
		)
		(property "Value" "TP_0.75mm_SMD"
			(at 292.735 176.53 0)
			(effects
				(font
					(size 1.27 1.27)
					(thickness 0.15)
				)
				(justify left bottom)
				(hide yes)
			)
		)
		(property "Footprint" "antmicro-footprints:TP_SMD_0.75mm"
			(at 292.735 179.07 0)
			(effects
				(font
					(size 1.27 1.27)
					(thickness 0.15)
				)
				(justify left bottom)
				(hide yes)
			)
		)
		(property "Datasheet" ""
			(at 299.72 185.42 0)
			(effects
				(font
					(size 1.27 1.27)
					(thickness 0.15)
				)
				(justify left bottom)
				(hide yes)
			)
		)
		(property "Description" ""
			(at 281.94 172.72 0)
			(effects
				(font
					(size 1.27 1.27)
				)
				(hide yes)
			)
		)
		(property "MPN" ""
			(at 292.735 184.15 0)
			(effects
				(font
					(size 1.27 1.27)
					(thickness 0.15)
				)
				(justify left bottom)
				(hide yes)
			)
		)
		(property "Manufacturer" ""
			(at 292.735 179.07 0)
			(effects
				(font
					(size 1.27 1.27)
					(thickness 0.15)
				)
				(justify left bottom)
				(hide yes)
			)
		)
		(property "Author" "Antmicro"
			(at 292.735 181.61 0)
			(effects
				(font
					(size 1.27 1.27)
					(thickness 0.15)
				)
				(justify left bottom)
				(hide yes)
			)
		)
		(property "License" "Apache-2.0"
			(at 292.735 184.15 0)
			(effects
				(font
					(size 1.27 1.27)
					(thickness 0.15)
				)
				(justify left bottom)
				(hide yes)
			)
		)
		(property "Public" "False"
			(at 292.1 186.69 0)
			(effects
				(font
					(size 1.27 1.27)
				)
				(justify left bottom)
				(hide yes)
			)
		)
		(pin "1"
		)
		(instances
			(project "com-express-7-baseboard"
				(path ""
					(reference "TP19")
					(unit 1)
				)
			)
		)
	)
	(symbol
		(lib_id "antmicropower:GND")
		(at 369.57 100.33 0)
		(unit 1)
		(exclude_from_sim no)
		(in_bom yes)
		(on_board yes)
		(dnp no)
		(property "Reference" "#PWR0223"
			(at 378.46 102.87 0)
			(effects
				(font
					(size 1.27 1.27)
					(thickness 0.15)
				)
				(justify left bottom)
				(hide yes)
			)
		)
		(property "Value" "GND"
			(at 369.57 104.14 0)
			(effects
				(font
					(size 1.27 1.27)
					(thickness 0.15)
				)
			)
		)
		(property "Footprint" ""
			(at 378.46 107.95 0)
			(effects
				(font
					(size 1.27 1.27)
					(thickness 0.15)
				)
				(justify left bottom)
				(hide yes)
			)
		)
		(property "Datasheet" ""
			(at 378.46 113.03 0)
			(effects
				(font
					(size 1.27 1.27)
					(thickness 0.15)
				)
				(justify left bottom)
				(hide yes)
			)
		)
		(property "Description" ""
			(at 369.57 100.33 0)
			(effects
				(font
					(size 1.27 1.27)
				)
				(hide yes)
			)
		)
		(property "Author" "Antmicro"
			(at 378.46 107.95 0)
			(effects
				(font
					(size 1.27 1.27)
					(thickness 0.15)
				)
				(justify left bottom)
				(hide yes)
			)
		)
		(property "License" "Apache-2.0"
			(at 378.46 110.49 0)
			(effects
				(font
					(size 1.27 1.27)
					(thickness 0.15)
				)
				(justify left bottom)
				(hide yes)
			)
		)
		(pin "1"
		)
		(instances
			(project "com-express-7-baseboard"
				(path ""
					(reference "#PWR0223")
					(unit 1)
				)
			)
		)
	)
	(symbol
		(lib_id "antmicroTestPoints:TP_0.75mm_SMD")
		(at 281.94 96.52 0)
		(unit 1)
		(exclude_from_sim no)
		(in_bom no)
		(on_board yes)
		(dnp no)
		(fields_autoplaced yes)
		(property "Reference" "TP17"
			(at 287.02 96.52 0)
			(effects
				(font
					(size 1.27 1.27)
					(thickness 0.15)
				)
				(justify left)
			)
		)
		(property "Value" "TP_0.75mm_SMD"
			(at 292.735 100.33 0)
			(effects
				(font
					(size 1.27 1.27)
					(thickness 0.15)
				)
				(justify left bottom)
				(hide yes)
			)
		)
		(property "Footprint" "antmicro-footprints:TP_SMD_0.75mm"
			(at 292.735 102.87 0)
			(effects
				(font
					(size 1.27 1.27)
					(thickness 0.15)
				)
				(justify left bottom)
				(hide yes)
			)
		)
		(property "Datasheet" ""
			(at 299.72 109.22 0)
			(effects
				(font
					(size 1.27 1.27)
					(thickness 0.15)
				)
				(justify left bottom)
				(hide yes)
			)
		)
		(property "Description" ""
			(at 281.94 96.52 0)
			(effects
				(font
					(size 1.27 1.27)
				)
				(hide yes)
			)
		)
		(property "MPN" ""
			(at 292.735 107.95 0)
			(effects
				(font
					(size 1.27 1.27)
					(thickness 0.15)
				)
				(justify left bottom)
				(hide yes)
			)
		)
		(property "Manufacturer" ""
			(at 292.735 102.87 0)
			(effects
				(font
					(size 1.27 1.27)
					(thickness 0.15)
				)
				(justify left bottom)
				(hide yes)
			)
		)
		(property "Author" "Antmicro"
			(at 292.735 105.41 0)
			(effects
				(font
					(size 1.27 1.27)
					(thickness 0.15)
				)
				(justify left bottom)
				(hide yes)
			)
		)
		(property "License" "Apache-2.0"
			(at 292.735 107.95 0)
			(effects
				(font
					(size 1.27 1.27)
					(thickness 0.15)
				)
				(justify left bottom)
				(hide yes)
			)
		)
		(property "Public" "False"
			(at 292.1 110.49 0)
			(effects
				(font
					(size 1.27 1.27)
				)
				(justify left bottom)
				(hide yes)
			)
		)
		(pin "1"
		)
		(instances
			(project "com-express-7-baseboard"
				(path ""
					(reference "TP17")
					(unit 1)
				)
			)
		)
	)
	(symbol
		(lib_id "antmicropower:GND")
		(at 246.38 275.59 0)
		(unit 1)
		(exclude_from_sim no)
		(in_bom yes)
		(on_board yes)
		(dnp no)
		(property "Reference" "#PWR0469"
			(at 246.38 281.94 0)
			(effects
				(font
					(size 1.27 1.27)
				)
				(justify left bottom)
				(hide yes)
			)
		)
		(property "Value" "GND"
			(at 244.475 280.67 0)
			(effects
				(font
					(size 1.27 1.27)
				)
				(justify left bottom)
			)
		)
		(property "Footprint" ""
			(at 246.38 275.59 0)
			(effects
				(font
					(size 1.27 1.27)
				)
				(justify left bottom)
				(hide yes)
			)
		)
		(property "Datasheet" ""
			(at 246.38 275.59 0)
			(effects
				(font
					(size 1.27 1.27)
				)
				(justify left bottom)
				(hide yes)
			)
		)
		(property "Description" ""
			(at 246.38 275.59 0)
			(effects
				(font
					(size 1.27 1.27)
				)
				(hide yes)
			)
		)
		(property "Author" "Antmicro"
			(at 255.27 283.21 0)
			(effects
				(font
					(size 1.27 1.27)
					(thickness 0.15)
				)
				(justify left bottom)
				(hide yes)
			)
		)
		(property "License" "Apache-2.0"
			(at 255.27 285.75 0)
			(effects
				(font
					(size 1.27 1.27)
					(thickness 0.15)
				)
				(justify left bottom)
				(hide yes)
			)
		)
		(pin "1"
		)
		(instances
			(project "com-express-7-baseboard"
				(path ""
					(reference "#PWR0469")
					(unit 1)
				)
			)
		)
	)
	(symbol
		(lib_id "antmicroTestPoints:TP_0.75mm_SMD")
		(at 281.94 177.8 0)
		(unit 1)
		(exclude_from_sim no)
		(in_bom no)
		(on_board yes)
		(dnp no)
		(fields_autoplaced yes)
		(property "Reference" "TP21"
			(at 287.02 177.8 0)
			(effects
				(font
					(size 1.27 1.27)
					(thickness 0.15)
				)
				(justify left)
			)
		)
		(property "Value" "TP_0.75mm_SMD"
			(at 292.735 181.61 0)
			(effects
				(font
					(size 1.27 1.27)
					(thickness 0.15)
				)
				(justify left bottom)
				(hide yes)
			)
		)
		(property "Footprint" "antmicro-footprints:TP_SMD_0.75mm"
			(at 292.735 184.15 0)
			(effects
				(font
					(size 1.27 1.27)
					(thickness 0.15)
				)
				(justify left bottom)
				(hide yes)
			)
		)
		(property "Datasheet" ""
			(at 299.72 190.5 0)
			(effects
				(font
					(size 1.27 1.27)
					(thickness 0.15)
				)
				(justify left bottom)
				(hide yes)
			)
		)
		(property "Description" ""
			(at 281.94 177.8 0)
			(effects
				(font
					(size 1.27 1.27)
				)
				(hide yes)
			)
		)
		(property "MPN" ""
			(at 292.735 189.23 0)
			(effects
				(font
					(size 1.27 1.27)
					(thickness 0.15)
				)
				(justify left bottom)
				(hide yes)
			)
		)
		(property "Manufacturer" ""
			(at 292.735 184.15 0)
			(effects
				(font
					(size 1.27 1.27)
					(thickness 0.15)
				)
				(justify left bottom)
				(hide yes)
			)
		)
		(property "Author" "Antmicro"
			(at 292.735 186.69 0)
			(effects
				(font
					(size 1.27 1.27)
					(thickness 0.15)
				)
				(justify left bottom)
				(hide yes)
			)
		)
		(property "License" "Apache-2.0"
			(at 292.735 189.23 0)
			(effects
				(font
					(size 1.27 1.27)
					(thickness 0.15)
				)
				(justify left bottom)
				(hide yes)
			)
		)
		(property "Public" "False"
			(at 292.1 191.77 0)
			(effects
				(font
					(size 1.27 1.27)
				)
				(justify left bottom)
				(hide yes)
			)
		)
		(pin "1"
		)
		(instances
			(project "com-express-7-baseboard"
				(path ""
					(reference "TP21")
					(unit 1)
				)
			)
		)
	)
	(symbol
		(lib_id "antmicroB2BConnectors:Plug_Bus_CE7_EPT_401-51501-51")
		(at 139.7 33.02 0)
		(unit 9)
		(exclude_from_sim no)
		(in_bom yes)
		(on_board yes)
		(dnp no)
		(fields_autoplaced yes)
		(property "Reference" "J12"
			(at 120.65 25.4 0)
			(effects
				(font
					(size 1.27 1.27)
					(thickness 0.15)
				)
			)
		)
		(property "Value" "Plug_Bus_CE7_EPT_401-51501-51"
			(at 193.04 45.72 0)
			(effects
				(font
					(size 1.27 1.27)
					(thickness 0.15)
				)
				(justify left bottom)
				(hide yes)
			)
		)
		(property "Footprint" "antmicro-footprints:EPT_401-51501-51"
			(at 193.04 48.26 0)
			(effects
				(font
					(size 1.27 1.27)
					(thickness 0.15)
				)
				(justify left bottom)
				(hide yes)
			)
		)
		(property "Datasheet" "https://www.farnell.com/datasheets/1905093.pdf"
			(at 193.04 50.8 0)
			(effects
				(font
					(size 1.27 1.27)
					(thickness 0.15)
				)
				(justify left bottom)
				(hide yes)
			)
		)
		(property "Description" ""
			(at 139.7 33.02 0)
			(effects
				(font
					(size 1.27 1.27)
				)
				(hide yes)
			)
		)
		(property "Author" "Antmicro"
			(at 193.04 53.34 0)
			(effects
				(font
					(size 1.27 1.27)
					(thickness 0.15)
				)
				(justify left bottom)
				(hide yes)
			)
		)
		(property "License" "Apache-2.0"
			(at 193.04 55.88 0)
			(effects
				(font
					(size 1.27 1.27)
					(thickness 0.15)
				)
				(justify left bottom)
				(hide yes)
			)
		)
		(property "Manufacturer" "ept"
			(at 193.04 38.1 0)
			(effects
				(font
					(size 1.27 1.27)
					(thickness 0.15)
				)
				(justify left bottom)
				(hide yes)
			)
		)
		(property "MPN" "401-51501-51"
			(at 120.65 27.94 0)
			(effects
				(font
					(size 1.27 1.27)
					(thickness 0.15)
				)
			)
		)
		(pin "C91"
		)
		(pin "C92"
		)
		(pin "A15"
		)
		(pin "A91"
		)
		(pin "C34"
		)
		(pin "C35"
		)
		(pin "D22"
		)
		(pin "D23"
		)
		(pin "D55"
		)
		(pin "D56"
		)
		(pin "C55"
		)
		(pin "C56"
		)
		(pin "C71"
		)
		(pin "C72"
		)
		(pin "C32"
		)
		(pin "C33"
		)
		(pin "B6"
		)
		(pin "B58"
		)
		(pin "B59"
		)
		(pin "D5"
		)
		(pin "D51"
		)
		(pin "A29"
		)
		(pin "D46"
		)
		(pin "D47"
		)
		(pin "C105"
		)
		(pin "C106"
		)
		(pin "A16"
		)
		(pin "B22"
		)
		(pin "B51"
		)
		(pin "B30"
		)
		(pin "A44"
		)
		(pin "C51"
		)
		(pin "C60"
		)
		(pin "A81"
		)
		(pin "A82"
		)
		(pin "D90"
		)
		(pin "D93"
		)
		(pin "B68"
		)
		(pin "B69"
		)
		(pin "C103"
		)
		(pin "C104"
		)
		(pin "C58"
		)
		(pin "C59"
		)
		(pin "D84"
		)
		(pin "D87"
		)
		(pin "A30"
		)
		(pin "B29"
		)
		(pin "A41"
		)
		(pin "C40"
		)
		(pin "C42"
		)
		(pin "D80"
		)
		(pin "D83"
		)
		(pin "B103"
		)
		(pin "A102"
		)
		(pin "C101"
		)
		(pin "C102"
		)
		(pin "D11"
		)
		(pin "D110"
		)
		(pin "B37"
		)
		(pin "B45"
		)
		(pin "C61"
		)
		(pin "C62"
		)
		(pin "A42"
		)
		(pin "B36"
		)
		(pin "B57"
		)
		(pin "D12"
		)
		(pin "D44"
		)
		(pin "D48"
		)
		(pin "B32"
		)
		(pin "B107"
		)
		(pin "B108"
		)
		(pin "B110"
		)
		(pin "B101"
		)
		(pin "C63"
		)
		(pin "C64"
		)
		(pin "B50"
		)
		(pin "A87"
		)
		(pin "A86"
		)
		(pin "B27"
		)
		(pin "D17"
		)
		(pin "D24"
		)
		(pin "D26"
		)
		(pin "D27"
		)
		(pin "A47"
		)
		(pin "C81"
		)
		(pin "C82"
		)
		(pin "C68"
		)
		(pin "C69"
		)
		(pin "A74"
		)
		(pin "A48"
		)
		(pin "A57"
		)
		(pin "A43"
		)
		(pin "A31"
		)
		(pin "D29"
		)
		(pin "D30"
		)
		(pin "C36"
		)
		(pin "C37"
		)
		(pin "C3"
		)
		(pin "A35"
		)
		(pin "A34"
		)
		(pin "B7"
		)
		(pin "B46"
		)
		(pin "B1"
		)
		(pin "B63"
		)
		(pin "A51"
		)
		(pin "A99"
		)
		(pin "B17"
		)
		(pin "C13"
		)
		(pin "C4"
		)
		(pin "B102"
		)
		(pin "C38"
		)
		(pin "C39"
		)
		(pin "B3"
		)
		(pin "A90"
		)
		(pin "A72"
		)
		(pin "B84"
		)
		(pin "D19"
		)
		(pin "D20"
		)
		(pin "D43"
		)
		(pin "D45"
		)
		(pin "A77"
		)
		(pin "A78"
		)
		(pin "B38"
		)
		(pin "B86"
		)
		(pin "D77"
		)
		(pin "D8"
		)
		(pin "A32"
		)
		(pin "B85"
		)
		(pin "D73"
		)
		(pin "D76"
		)
		(pin "D63"
		)
		(pin "D64"
		)
		(pin "D67"
		)
		(pin "D70"
		)
		(pin "B83"
		)
		(pin "D81"
		)
		(pin "D82"
		)
		(pin "B41"
		)
		(pin "D49"
		)
		(pin "D50"
		)
		(pin "A75"
		)
		(pin "D2"
		)
		(pin "D21"
		)
		(pin "C78"
		)
		(pin "C79"
		)
		(pin "B19"
		)
		(pin "B39"
		)
		(pin "A12"
		)
		(pin "B66"
		)
		(pin "D4"
		)
		(pin "D85"
		)
		(pin "D86"
		)
		(pin "A105"
		)
		(pin "B90"
		)
		(pin "A22"
		)
		(pin "A109"
		)
		(pin "B88"
		)
		(pin "B14"
		)
		(pin "B71"
		)
		(pin "B52"
		)
		(pin "B53"
		)
		(pin "D7"
		)
		(pin "A108"
		)
		(pin "C85"
		)
		(pin "C86"
		)
		(pin "B61"
		)
		(pin "B62"
		)
		(pin "D68"
		)
		(pin "D69"
		)
		(pin "A88"
		)
		(pin "A89"
		)
		(pin "D6"
		)
		(pin "C7"
		)
		(pin "B33"
		)
		(pin "D88"
		)
		(pin "D89"
		)
		(pin "B26"
		)
		(pin "A76"
		)
		(pin "D101"
		)
		(pin "D102"
		)
		(pin "B12"
		)
		(pin "C15"
		)
		(pin "C16"
		)
		(pin "A18"
		)
		(pin "A13"
		)
		(pin "A66"
		)
		(pin "C26"
		)
		(pin "C27"
		)
		(pin "A101"
		)
		(pin "A17"
		)
		(pin "B96"
		)
		(pin "C22"
		)
		(pin "C23"
		)
		(pin "A79"
		)
		(pin "A54"
		)
		(pin "C41"
		)
		(pin "C44"
		)
		(pin "A100"
		)
		(pin "A67"
		)
		(pin "A10"
		)
		(pin "A14"
		)
		(pin "C6"
		)
		(pin "A84"
		)
		(pin "B91"
		)
		(pin "C29"
		)
		(pin "C30"
		)
		(pin "A37"
		)
		(pin "A39"
		)
		(pin "B10"
		)
		(pin "B34"
		)
		(pin "C54"
		)
		(pin "C57"
		)
		(pin "B64"
		)
		(pin "B65"
		)
		(pin "A58"
		)
		(pin "A59"
		)
		(pin "B92"
		)
		(pin "C43"
		)
		(pin "C45"
		)
		(pin "A97"
		)
		(pin "A11"
		)
		(pin "A61"
		)
		(pin "A62"
		)
		(pin "B48"
		)
		(pin "B54"
		)
		(pin "D71"
		)
		(pin "D72"
		)
		(pin "A26"
		)
		(pin "A36"
		)
		(pin "D31"
		)
		(pin "D36"
		)
		(pin "B76"
		)
		(pin "B21"
		)
		(pin "B24"
		)
		(pin "B94"
		)
		(pin "D3"
		)
		(pin "B79"
		)
		(pin "A85"
		)
		(pin "A23"
		)
		(pin "A25"
		)
		(pin "A24"
		)
		(pin "D14"
		)
		(pin "D18"
		)
		(pin "B15"
		)
		(pin "A107"
		)
		(pin "A98"
		)
		(pin "D9"
		)
		(pin "B44"
		)
		(pin "A4"
		)
		(pin "C28"
		)
		(pin "C31"
		)
		(pin "A9"
		)
		(pin "C49"
		)
		(pin "C50"
		)
		(pin "A83"
		)
		(pin "A110"
		)
		(pin "D52"
		)
		(pin "D53"
		)
		(pin "A40"
		)
		(pin "A71"
		)
		(pin "D98"
		)
		(pin "D99"
		)
		(pin "D40"
		)
		(pin "D42"
		)
		(pin "D37"
		)
		(pin "D41"
		)
		(pin "C109"
		)
		(pin "C11"
		)
		(pin "A106"
		)
		(pin "A3"
		)
		(pin "B109"
		)
		(pin "B40"
		)
		(pin "C70"
		)
		(pin "C73"
		)
		(pin "D13"
		)
		(pin "A1"
		)
		(pin "A46"
		)
		(pin "A20"
		)
		(pin "A104"
		)
		(pin "C9"
		)
		(pin "C110"
		)
		(pin "C14"
		)
		(pin "B23"
		)
		(pin "A93"
		)
		(pin "B89"
		)
		(pin "B87"
		)
		(pin "D54"
		)
		(pin "D60"
		)
		(pin "A21"
		)
		(pin "B93"
		)
		(pin "A70"
		)
		(pin "A60"
		)
		(pin "B97"
		)
		(pin "B95"
		)
		(pin "D38"
		)
		(pin "D39"
		)
		(pin "A50"
		)
		(pin "A52"
		)
		(pin "A53"
		)
		(pin "D91"
		)
		(pin "D92"
		)
		(pin "C67"
		)
		(pin "D57"
		)
		(pin "A96"
		)
		(pin "A92"
		)
		(pin "B70"
		)
		(pin "C46"
		)
		(pin "C47"
		)
		(pin "B4"
		)
		(pin "A64"
		)
		(pin "A65"
		)
		(pin "B43"
		)
		(pin "C21"
		)
		(pin "C25"
		)
		(pin "B42"
		)
		(pin "C19"
		)
		(pin "C20"
		)
		(pin "C18"
		)
		(pin "C2"
		)
		(pin "C107"
		)
		(pin "C108"
		)
		(pin "B35"
		)
		(pin "A28"
		)
		(pin "B11"
		)
		(pin "A103"
		)
		(pin "C97"
		)
		(pin "D1"
		)
		(pin "B98"
		)
		(pin "A19"
		)
		(pin "A68"
		)
		(pin "A69"
		)
		(pin "B55"
		)
		(pin "B56"
		)
		(pin "A8"
		)
		(pin "A33"
		)
		(pin "A95"
		)
		(pin "D96"
		)
		(pin "D97"
		)
		(pin "B31"
		)
		(pin "B105"
		)
		(pin "B100"
		)
		(pin "C65"
		)
		(pin "C66"
		)
		(pin "B104"
		)
		(pin "D61"
		)
		(pin "D62"
		)
		(pin "D78"
		)
		(pin "D79"
		)
		(pin "C83"
		)
		(pin "C84"
		)
		(pin "D74"
		)
		(pin "D75"
		)
		(pin "A45"
		)
		(pin "D106"
		)
		(pin "D107"
		)
		(pin "C8"
		)
		(pin "C80"
		)
		(pin "C87"
		)
		(pin "C90"
		)
		(pin "D58"
		)
		(pin "D59"
		)
		(pin "D104"
		)
		(pin "D105"
		)
		(pin "C93"
		)
		(pin "C96"
		)
		(pin "B73"
		)
		(pin "D108"
		)
		(pin "D109"
		)
		(pin "B20"
		)
		(pin "A27"
		)
		(pin "D34"
		)
		(pin "D35"
		)
		(pin "C17"
		)
		(pin "C24"
		)
		(pin "B49"
		)
		(pin "A6"
		)
		(pin "B5"
		)
		(pin "B99"
		)
		(pin "B25"
		)
		(pin "D94"
		)
		(pin "D95"
		)
		(pin "B106"
		)
		(pin "B67"
		)
		(pin "A2"
		)
		(pin "B13"
		)
		(pin "A49"
		)
		(pin "C52"
		)
		(pin "C53"
		)
		(pin "B72"
		)
		(pin "C94"
		)
		(pin "C95"
		)
		(pin "B74"
		)
		(pin "D10"
		)
		(pin "B75"
		)
		(pin "B77"
		)
		(pin "C98"
		)
		(pin "C99"
		)
		(pin "A7"
		)
		(pin "C88"
		)
		(pin "C89"
		)
		(pin "C10"
		)
		(pin "B78"
		)
		(pin "B81"
		)
		(pin "B28"
		)
		(pin "A63"
		)
		(pin "C76"
		)
		(pin "C77"
		)
		(pin "A55"
		)
		(pin "A56"
		)
		(pin "C48"
		)
		(pin "C5"
		)
		(pin "A5"
		)
		(pin "C1"
		)
		(pin "C100"
		)
		(pin "B47"
		)
		(pin "C74"
		)
		(pin "C75"
		)
		(pin "C12"
		)
		(pin "B80"
		)
		(pin "D15"
		)
		(pin "D16"
		)
		(pin "D100"
		)
		(pin "D103"
		)
		(pin "B2"
		)
		(pin "B9"
		)
		(pin "A94"
		)
		(pin "B82"
		)
		(pin "D25"
		)
		(pin "D28"
		)
		(pin "B16"
		)
		(pin "D65"
		)
		(pin "D66"
		)
		(pin "D32"
		)
		(pin "D33"
		)
		(pin "B8"
		)
		(pin "B60"
		)
		(pin "A38"
		)
		(pin "A73"
		)
		(pin "A80"
		)
		(pin "B18"
		)
		(pin "MP"
		)
		(instances
			(project "com-express-7-baseboard"
				(path ""
					(reference "J12")
					(unit 9)
				)
			)
		)
	)
	(symbol
		(lib_id "antmicroTestPoints:TP_0.75mm_SMD")
		(at 281.94 170.18 0)
		(unit 1)
		(exclude_from_sim no)
		(in_bom no)
		(on_board yes)
		(dnp no)
		(fields_autoplaced yes)
		(property "Reference" "TP18"
			(at 287.02 170.18 0)
			(effects
				(font
					(size 1.27 1.27)
					(thickness 0.15)
				)
				(justify left)
			)
		)
		(property "Value" "TP_0.75mm_SMD"
			(at 292.735 173.99 0)
			(effects
				(font
					(size 1.27 1.27)
					(thickness 0.15)
				)
				(justify left bottom)
				(hide yes)
			)
		)
		(property "Footprint" "antmicro-footprints:TP_SMD_0.75mm"
			(at 292.735 176.53 0)
			(effects
				(font
					(size 1.27 1.27)
					(thickness 0.15)
				)
				(justify left bottom)
				(hide yes)
			)
		)
		(property "Datasheet" ""
			(at 299.72 182.88 0)
			(effects
				(font
					(size 1.27 1.27)
					(thickness 0.15)
				)
				(justify left bottom)
				(hide yes)
			)
		)
		(property "Description" ""
			(at 281.94 170.18 0)
			(effects
				(font
					(size 1.27 1.27)
				)
				(hide yes)
			)
		)
		(property "MPN" ""
			(at 292.735 181.61 0)
			(effects
				(font
					(size 1.27 1.27)
					(thickness 0.15)
				)
				(justify left bottom)
				(hide yes)
			)
		)
		(property "Manufacturer" ""
			(at 292.735 176.53 0)
			(effects
				(font
					(size 1.27 1.27)
					(thickness 0.15)
				)
				(justify left bottom)
				(hide yes)
			)
		)
		(property "Author" "Antmicro"
			(at 292.735 179.07 0)
			(effects
				(font
					(size 1.27 1.27)
					(thickness 0.15)
				)
				(justify left bottom)
				(hide yes)
			)
		)
		(property "License" "Apache-2.0"
			(at 292.735 181.61 0)
			(effects
				(font
					(size 1.27 1.27)
					(thickness 0.15)
				)
				(justify left bottom)
				(hide yes)
			)
		)
		(property "Public" "False"
			(at 292.1 184.15 0)
			(effects
				(font
					(size 1.27 1.27)
				)
				(justify left bottom)
				(hide yes)
			)
		)
		(pin "1"
		)
		(instances
			(project "com-express-7-baseboard"
				(path ""
					(reference "TP18")
					(unit 1)
				)
			)
		)
	)
	(symbol
		(lib_id "antmicroMechanicalParts:Spacer_Drill3.7mm_H5mm_9774050151R")
		(at 247.65 252.73 0)
		(unit 1)
		(exclude_from_sim no)
		(in_bom yes)
		(on_board yes)
		(dnp no)
		(fields_autoplaced yes)
		(property "Reference" "H7"
			(at 256.54 251.46 0)
			(effects
				(font
					(size 1.27 1.27)
					(thickness 0.15)
				)
				(justify left)
			)
		)
		(property "Value" "Spacer_Drill3.7mm_H5mm_9774050151R"
			(at 256.54 254 0)
			(effects
				(font
					(size 1.27 1.27)
					(thickness 0.15)
				)
				(justify left)
			)
		)
		(property "Footprint" "antmicro-footprints:Spacer_Drill3.7mm_H5mm_9774050151R"
			(at 270.51 260.35 0)
			(effects
				(font
					(size 1.27 1.27)
					(thickness 0.15)
				)
				(justify left bottom)
				(hide yes)
			)
		)
		(property "Datasheet" "https://www.we-online.com/catalog/datasheet/9774050151.pdf"
			(at 270.51 262.89 0)
			(effects
				(font
					(size 1.27 1.27)
					(thickness 0.15)
				)
				(justify left bottom)
				(hide yes)
			)
		)
		(property "Description" ""
			(at 247.65 252.73 0)
			(effects
				(font
					(size 1.27 1.27)
				)
				(hide yes)
			)
		)
		(property "Manufacturer" "Würth Elektronik"
			(at 270.51 265.43 0)
			(effects
				(font
					(size 1.27 1.27)
					(thickness 0.15)
				)
				(justify left bottom)
				(hide yes)
			)
		)
		(property "MPN" "9774050151R"
			(at 270.51 267.97 0)
			(effects
				(font
					(size 1.27 1.27)
					(thickness 0.15)
				)
				(justify left bottom)
				(hide yes)
			)
		)
		(property "Author" "Antmicro"
			(at 270.51 270.51 0)
			(effects
				(font
					(size 1.27 1.27)
					(thickness 0.15)
				)
				(justify left bottom)
				(hide yes)
			)
		)
		(property "License" "Apache-2.0"
			(at 270.51 273.05 0)
			(effects
				(font
					(size 1.27 1.27)
					(thickness 0.15)
				)
				(justify left bottom)
				(hide yes)
			)
		)
		(pin "1"
		)
		(instances
			(project "com-express-7-baseboard"
				(path ""
					(reference "H7")
					(unit 1)
				)
			)
		)
	)
	(symbol
		(lib_id "antmicroMechanicalParts:Spacer_Drill3.7mm_H5mm_9774050151R")
		(at 247.65 265.43 0)
		(unit 1)
		(exclude_from_sim no)
		(in_bom yes)
		(on_board yes)
		(dnp no)
		(fields_autoplaced yes)
		(property "Reference" "H9"
			(at 256.54 264.16 0)
			(effects
				(font
					(size 1.27 1.27)
					(thickness 0.15)
				)
				(justify left)
			)
		)
		(property "Value" "Spacer_Drill3.7mm_H5mm_9774050151R"
			(at 256.54 266.7 0)
			(effects
				(font
					(size 1.27 1.27)
					(thickness 0.15)
				)
				(justify left)
			)
		)
		(property "Footprint" "antmicro-footprints:Spacer_Drill3.7mm_H5mm_9774050151R"
			(at 270.51 273.05 0)
			(effects
				(font
					(size 1.27 1.27)
					(thickness 0.15)
				)
				(justify left bottom)
				(hide yes)
			)
		)
		(property "Datasheet" "https://www.we-online.com/catalog/datasheet/9774050151.pdf"
			(at 270.51 275.59 0)
			(effects
				(font
					(size 1.27 1.27)
					(thickness 0.15)
				)
				(justify left bottom)
				(hide yes)
			)
		)
		(property "Description" ""
			(at 247.65 265.43 0)
			(effects
				(font
					(size 1.27 1.27)
				)
				(hide yes)
			)
		)
		(property "Manufacturer" "Würth Elektronik"
			(at 270.51 278.13 0)
			(effects
				(font
					(size 1.27 1.27)
					(thickness 0.15)
				)
				(justify left bottom)
				(hide yes)
			)
		)
		(property "MPN" "9774050151R"
			(at 270.51 280.67 0)
			(effects
				(font
					(size 1.27 1.27)
					(thickness 0.15)
				)
				(justify left bottom)
				(hide yes)
			)
		)
		(property "Author" "Antmicro"
			(at 270.51 283.21 0)
			(effects
				(font
					(size 1.27 1.27)
					(thickness 0.15)
				)
				(justify left bottom)
				(hide yes)
			)
		)
		(property "License" "Apache-2.0"
			(at 270.51 285.75 0)
			(effects
				(font
					(size 1.27 1.27)
					(thickness 0.15)
				)
				(justify left bottom)
				(hide yes)
			)
		)
		(pin "1"
		)
		(instances
			(project "com-express-7-baseboard"
				(path ""
					(reference "H9")
					(unit 1)
				)
			)
		)
	)
	(symbol
		(lib_id "antmicroB2BConnectors:Plug_Bus_CE7_EPT_401-51501-51")
		(at 139.7 167.64 0)
		(unit 15)
		(exclude_from_sim no)
		(in_bom yes)
		(on_board yes)
		(dnp no)
		(fields_autoplaced yes)
		(property "Reference" "J12"
			(at 120.65 160.02 0)
			(effects
				(font
					(size 1.27 1.27)
					(thickness 0.15)
				)
			)
		)
		(property "Value" "Plug_Bus_CE7_EPT_401-51501-51"
			(at 193.04 180.34 0)
			(effects
				(font
					(size 1.27 1.27)
					(thickness 0.15)
				)
				(justify left bottom)
				(hide yes)
			)
		)
		(property "Footprint" "antmicro-footprints:EPT_401-51501-51"
			(at 193.04 182.88 0)
			(effects
				(font
					(size 1.27 1.27)
					(thickness 0.15)
				)
				(justify left bottom)
				(hide yes)
			)
		)
		(property "Datasheet" "https://www.farnell.com/datasheets/1905093.pdf"
			(at 193.04 185.42 0)
			(effects
				(font
					(size 1.27 1.27)
					(thickness 0.15)
				)
				(justify left bottom)
				(hide yes)
			)
		)
		(property "Description" ""
			(at 139.7 167.64 0)
			(effects
				(font
					(size 1.27 1.27)
				)
				(hide yes)
			)
		)
		(property "Author" "Antmicro"
			(at 193.04 187.96 0)
			(effects
				(font
					(size 1.27 1.27)
					(thickness 0.15)
				)
				(justify left bottom)
				(hide yes)
			)
		)
		(property "License" "Apache-2.0"
			(at 193.04 190.5 0)
			(effects
				(font
					(size 1.27 1.27)
					(thickness 0.15)
				)
				(justify left bottom)
				(hide yes)
			)
		)
		(property "Manufacturer" "ept"
			(at 193.04 172.72 0)
			(effects
				(font
					(size 1.27 1.27)
					(thickness 0.15)
				)
				(justify left bottom)
				(hide yes)
			)
		)
		(property "MPN" "401-51501-51"
			(at 120.65 162.56 0)
			(effects
				(font
					(size 1.27 1.27)
					(thickness 0.15)
				)
			)
		)
		(pin "C91"
		)
		(pin "C92"
		)
		(pin "A15"
		)
		(pin "A91"
		)
		(pin "C34"
		)
		(pin "C35"
		)
		(pin "D22"
		)
		(pin "D23"
		)
		(pin "D55"
		)
		(pin "D56"
		)
		(pin "C55"
		)
		(pin "C56"
		)
		(pin "C71"
		)
		(pin "C72"
		)
		(pin "C32"
		)
		(pin "C33"
		)
		(pin "B6"
		)
		(pin "B58"
		)
		(pin "B59"
		)
		(pin "D5"
		)
		(pin "D51"
		)
		(pin "A29"
		)
		(pin "D46"
		)
		(pin "D47"
		)
		(pin "C105"
		)
		(pin "C106"
		)
		(pin "A16"
		)
		(pin "B22"
		)
		(pin "B51"
		)
		(pin "B30"
		)
		(pin "A44"
		)
		(pin "C51"
		)
		(pin "C60"
		)
		(pin "A81"
		)
		(pin "A82"
		)
		(pin "D90"
		)
		(pin "D93"
		)
		(pin "B68"
		)
		(pin "B69"
		)
		(pin "C103"
		)
		(pin "C104"
		)
		(pin "C58"
		)
		(pin "C59"
		)
		(pin "D84"
		)
		(pin "D87"
		)
		(pin "A30"
		)
		(pin "B29"
		)
		(pin "A41"
		)
		(pin "C40"
		)
		(pin "C42"
		)
		(pin "D80"
		)
		(pin "D83"
		)
		(pin "B103"
		)
		(pin "A102"
		)
		(pin "C101"
		)
		(pin "C102"
		)
		(pin "D11"
		)
		(pin "D110"
		)
		(pin "B37"
		)
		(pin "B45"
		)
		(pin "C61"
		)
		(pin "C62"
		)
		(pin "A42"
		)
		(pin "B36"
		)
		(pin "B57"
		)
		(pin "D12"
		)
		(pin "D44"
		)
		(pin "D48"
		)
		(pin "B32"
		)
		(pin "B107"
		)
		(pin "B108"
		)
		(pin "B110"
		)
		(pin "B101"
		)
		(pin "C63"
		)
		(pin "C64"
		)
		(pin "B50"
		)
		(pin "A87"
		)
		(pin "A86"
		)
		(pin "B27"
		)
		(pin "D17"
		)
		(pin "D24"
		)
		(pin "D26"
		)
		(pin "D27"
		)
		(pin "A47"
		)
		(pin "C81"
		)
		(pin "C82"
		)
		(pin "C68"
		)
		(pin "C69"
		)
		(pin "A74"
		)
		(pin "A48"
		)
		(pin "A57"
		)
		(pin "A43"
		)
		(pin "A31"
		)
		(pin "D29"
		)
		(pin "D30"
		)
		(pin "C36"
		)
		(pin "C37"
		)
		(pin "C3"
		)
		(pin "A35"
		)
		(pin "A34"
		)
		(pin "B7"
		)
		(pin "B46"
		)
		(pin "B1"
		)
		(pin "B63"
		)
		(pin "A51"
		)
		(pin "A99"
		)
		(pin "B17"
		)
		(pin "C13"
		)
		(pin "C4"
		)
		(pin "B102"
		)
		(pin "C38"
		)
		(pin "C39"
		)
		(pin "B3"
		)
		(pin "A90"
		)
		(pin "A72"
		)
		(pin "B84"
		)
		(pin "D19"
		)
		(pin "D20"
		)
		(pin "D43"
		)
		(pin "D45"
		)
		(pin "A77"
		)
		(pin "A78"
		)
		(pin "B38"
		)
		(pin "B86"
		)
		(pin "D77"
		)
		(pin "D8"
		)
		(pin "A32"
		)
		(pin "B85"
		)
		(pin "D73"
		)
		(pin "D76"
		)
		(pin "D63"
		)
		(pin "D64"
		)
		(pin "D67"
		)
		(pin "D70"
		)
		(pin "B83"
		)
		(pin "D81"
		)
		(pin "D82"
		)
		(pin "B41"
		)
		(pin "D49"
		)
		(pin "D50"
		)
		(pin "A75"
		)
		(pin "D2"
		)
		(pin "D21"
		)
		(pin "C78"
		)
		(pin "C79"
		)
		(pin "B19"
		)
		(pin "B39"
		)
		(pin "A12"
		)
		(pin "B66"
		)
		(pin "D4"
		)
		(pin "D85"
		)
		(pin "D86"
		)
		(pin "A105"
		)
		(pin "B90"
		)
		(pin "A22"
		)
		(pin "A109"
		)
		(pin "B88"
		)
		(pin "B14"
		)
		(pin "B71"
		)
		(pin "B52"
		)
		(pin "B53"
		)
		(pin "D7"
		)
		(pin "A108"
		)
		(pin "C85"
		)
		(pin "C86"
		)
		(pin "B61"
		)
		(pin "B62"
		)
		(pin "D68"
		)
		(pin "D69"
		)
		(pin "A88"
		)
		(pin "A89"
		)
		(pin "D6"
		)
		(pin "C7"
		)
		(pin "B33"
		)
		(pin "D88"
		)
		(pin "D89"
		)
		(pin "B26"
		)
		(pin "A76"
		)
		(pin "D101"
		)
		(pin "D102"
		)
		(pin "B12"
		)
		(pin "C15"
		)
		(pin "C16"
		)
		(pin "A18"
		)
		(pin "A13"
		)
		(pin "A66"
		)
		(pin "C26"
		)
		(pin "C27"
		)
		(pin "A101"
		)
		(pin "A17"
		)
		(pin "B96"
		)
		(pin "C22"
		)
		(pin "C23"
		)
		(pin "A79"
		)
		(pin "A54"
		)
		(pin "C41"
		)
		(pin "C44"
		)
		(pin "A100"
		)
		(pin "A67"
		)
		(pin "A10"
		)
		(pin "A14"
		)
		(pin "C6"
		)
		(pin "A84"
		)
		(pin "B91"
		)
		(pin "C29"
		)
		(pin "C30"
		)
		(pin "A37"
		)
		(pin "A39"
		)
		(pin "B10"
		)
		(pin "B34"
		)
		(pin "C54"
		)
		(pin "C57"
		)
		(pin "B64"
		)
		(pin "B65"
		)
		(pin "A58"
		)
		(pin "A59"
		)
		(pin "B92"
		)
		(pin "C43"
		)
		(pin "C45"
		)
		(pin "A97"
		)
		(pin "A11"
		)
		(pin "A61"
		)
		(pin "A62"
		)
		(pin "B48"
		)
		(pin "B54"
		)
		(pin "D71"
		)
		(pin "D72"
		)
		(pin "A26"
		)
		(pin "A36"
		)
		(pin "D31"
		)
		(pin "D36"
		)
		(pin "B76"
		)
		(pin "B21"
		)
		(pin "B24"
		)
		(pin "B94"
		)
		(pin "D3"
		)
		(pin "B79"
		)
		(pin "A85"
		)
		(pin "A23"
		)
		(pin "A25"
		)
		(pin "A24"
		)
		(pin "D14"
		)
		(pin "D18"
		)
		(pin "B15"
		)
		(pin "A107"
		)
		(pin "A98"
		)
		(pin "D9"
		)
		(pin "B44"
		)
		(pin "A4"
		)
		(pin "C28"
		)
		(pin "C31"
		)
		(pin "A9"
		)
		(pin "C49"
		)
		(pin "C50"
		)
		(pin "A83"
		)
		(pin "A110"
		)
		(pin "D52"
		)
		(pin "D53"
		)
		(pin "A40"
		)
		(pin "A71"
		)
		(pin "D98"
		)
		(pin "D99"
		)
		(pin "D40"
		)
		(pin "D42"
		)
		(pin "D37"
		)
		(pin "D41"
		)
		(pin "C109"
		)
		(pin "C11"
		)
		(pin "A106"
		)
		(pin "A3"
		)
		(pin "B109"
		)
		(pin "B40"
		)
		(pin "C70"
		)
		(pin "C73"
		)
		(pin "D13"
		)
		(pin "A1"
		)
		(pin "A46"
		)
		(pin "A20"
		)
		(pin "A104"
		)
		(pin "C9"
		)
		(pin "C110"
		)
		(pin "C14"
		)
		(pin "B23"
		)
		(pin "A93"
		)
		(pin "B89"
		)
		(pin "B87"
		)
		(pin "D54"
		)
		(pin "D60"
		)
		(pin "A21"
		)
		(pin "B93"
		)
		(pin "A70"
		)
		(pin "A60"
		)
		(pin "B97"
		)
		(pin "B95"
		)
		(pin "D38"
		)
		(pin "D39"
		)
		(pin "A50"
		)
		(pin "A52"
		)
		(pin "A53"
		)
		(pin "D91"
		)
		(pin "D92"
		)
		(pin "C67"
		)
		(pin "D57"
		)
		(pin "A96"
		)
		(pin "A92"
		)
		(pin "B70"
		)
		(pin "C46"
		)
		(pin "C47"
		)
		(pin "B4"
		)
		(pin "A64"
		)
		(pin "A65"
		)
		(pin "B43"
		)
		(pin "C21"
		)
		(pin "C25"
		)
		(pin "B42"
		)
		(pin "C19"
		)
		(pin "C20"
		)
		(pin "C18"
		)
		(pin "C2"
		)
		(pin "C107"
		)
		(pin "C108"
		)
		(pin "B35"
		)
		(pin "A28"
		)
		(pin "B11"
		)
		(pin "A103"
		)
		(pin "C97"
		)
		(pin "D1"
		)
		(pin "B98"
		)
		(pin "A19"
		)
		(pin "A68"
		)
		(pin "A69"
		)
		(pin "B55"
		)
		(pin "B56"
		)
		(pin "A8"
		)
		(pin "A33"
		)
		(pin "A95"
		)
		(pin "D96"
		)
		(pin "D97"
		)
		(pin "B31"
		)
		(pin "B105"
		)
		(pin "B100"
		)
		(pin "C65"
		)
		(pin "C66"
		)
		(pin "B104"
		)
		(pin "D61"
		)
		(pin "D62"
		)
		(pin "D78"
		)
		(pin "D79"
		)
		(pin "C83"
		)
		(pin "C84"
		)
		(pin "D74"
		)
		(pin "D75"
		)
		(pin "A45"
		)
		(pin "D106"
		)
		(pin "D107"
		)
		(pin "C8"
		)
		(pin "C80"
		)
		(pin "C87"
		)
		(pin "C90"
		)
		(pin "D58"
		)
		(pin "D59"
		)
		(pin "D104"
		)
		(pin "D105"
		)
		(pin "C93"
		)
		(pin "C96"
		)
		(pin "B73"
		)
		(pin "D108"
		)
		(pin "D109"
		)
		(pin "B20"
		)
		(pin "A27"
		)
		(pin "D34"
		)
		(pin "D35"
		)
		(pin "C17"
		)
		(pin "C24"
		)
		(pin "B49"
		)
		(pin "A6"
		)
		(pin "B5"
		)
		(pin "B99"
		)
		(pin "B25"
		)
		(pin "D94"
		)
		(pin "D95"
		)
		(pin "B106"
		)
		(pin "B67"
		)
		(pin "A2"
		)
		(pin "B13"
		)
		(pin "A49"
		)
		(pin "C52"
		)
		(pin "C53"
		)
		(pin "B72"
		)
		(pin "C94"
		)
		(pin "C95"
		)
		(pin "B74"
		)
		(pin "D10"
		)
		(pin "B75"
		)
		(pin "B77"
		)
		(pin "C98"
		)
		(pin "C99"
		)
		(pin "A7"
		)
		(pin "C88"
		)
		(pin "C89"
		)
		(pin "C10"
		)
		(pin "B78"
		)
		(pin "B81"
		)
		(pin "B28"
		)
		(pin "A63"
		)
		(pin "C76"
		)
		(pin "C77"
		)
		(pin "A55"
		)
		(pin "A56"
		)
		(pin "C48"
		)
		(pin "C5"
		)
		(pin "A5"
		)
		(pin "C1"
		)
		(pin "C100"
		)
		(pin "B47"
		)
		(pin "C74"
		)
		(pin "C75"
		)
		(pin "C12"
		)
		(pin "B80"
		)
		(pin "D15"
		)
		(pin "D16"
		)
		(pin "D100"
		)
		(pin "D103"
		)
		(pin "B2"
		)
		(pin "B9"
		)
		(pin "A94"
		)
		(pin "B82"
		)
		(pin "D25"
		)
		(pin "D28"
		)
		(pin "B16"
		)
		(pin "D65"
		)
		(pin "D66"
		)
		(pin "D32"
		)
		(pin "D33"
		)
		(pin "B8"
		)
		(pin "B60"
		)
		(pin "A38"
		)
		(pin "A73"
		)
		(pin "A80"
		)
		(pin "B18"
		)
		(pin "MP"
		)
		(instances
			(project "com-express-7-baseboard"
				(path ""
					(reference "J12")
					(unit 15)
				)
			)
		)
	)
	(symbol
		(lib_id "antmicroMechanicalParts:Spacer_Drill3.7mm_H5mm_9774050151R")
		(at 247.65 271.78 0)
		(unit 1)
		(exclude_from_sim no)
		(in_bom yes)
		(on_board yes)
		(dnp no)
		(fields_autoplaced yes)
		(property "Reference" "H10"
			(at 256.54 270.51 0)
			(effects
				(font
					(size 1.27 1.27)
					(thickness 0.15)
				)
				(justify left)
			)
		)
		(property "Value" "Spacer_Drill3.7mm_H5mm_9774050151R"
			(at 256.54 273.05 0)
			(effects
				(font
					(size 1.27 1.27)
					(thickness 0.15)
				)
				(justify left)
			)
		)
		(property "Footprint" "antmicro-footprints:Spacer_Drill3.7mm_H5mm_9774050151R"
			(at 270.51 279.4 0)
			(effects
				(font
					(size 1.27 1.27)
					(thickness 0.15)
				)
				(justify left bottom)
				(hide yes)
			)
		)
		(property "Datasheet" "https://www.we-online.com/catalog/datasheet/9774050151.pdf"
			(at 270.51 281.94 0)
			(effects
				(font
					(size 1.27 1.27)
					(thickness 0.15)
				)
				(justify left bottom)
				(hide yes)
			)
		)
		(property "Description" ""
			(at 247.65 271.78 0)
			(effects
				(font
					(size 1.27 1.27)
				)
				(hide yes)
			)
		)
		(property "Manufacturer" "Würth Elektronik"
			(at 270.51 284.48 0)
			(effects
				(font
					(size 1.27 1.27)
					(thickness 0.15)
				)
				(justify left bottom)
				(hide yes)
			)
		)
		(property "MPN" "9774050151R"
			(at 270.51 287.02 0)
			(effects
				(font
					(size 1.27 1.27)
					(thickness 0.15)
				)
				(justify left bottom)
				(hide yes)
			)
		)
		(property "Author" "Antmicro"
			(at 270.51 289.56 0)
			(effects
				(font
					(size 1.27 1.27)
					(thickness 0.15)
				)
				(justify left bottom)
				(hide yes)
			)
		)
		(property "License" "Apache-2.0"
			(at 270.51 292.1 0)
			(effects
				(font
					(size 1.27 1.27)
					(thickness 0.15)
				)
				(justify left bottom)
				(hide yes)
			)
		)
		(pin "1"
		)
		(instances
			(project "com-express-7-baseboard"
				(path ""
					(reference "H10")
					(unit 1)
				)
			)
		)
	)
	(symbol
		(lib_id "antmicroB2BConnectors:Plug_Bus_CE7_EPT_401-51501-51")
		(at 68.58 33.02 0)
		(unit 14)
		(exclude_from_sim no)
		(in_bom yes)
		(on_board yes)
		(dnp no)
		(fields_autoplaced yes)
		(property "Reference" "J12"
			(at 49.53 25.4 0)
			(effects
				(font
					(size 1.27 1.27)
					(thickness 0.15)
				)
			)
		)
		(property "Value" "Plug_Bus_CE7_EPT_401-51501-51"
			(at 121.92 45.72 0)
			(effects
				(font
					(size 1.27 1.27)
					(thickness 0.15)
				)
				(justify left bottom)
				(hide yes)
			)
		)
		(property "Footprint" "antmicro-footprints:EPT_401-51501-51"
			(at 121.92 48.26 0)
			(effects
				(font
					(size 1.27 1.27)
					(thickness 0.15)
				)
				(justify left bottom)
				(hide yes)
			)
		)
		(property "Datasheet" "https://www.farnell.com/datasheets/1905093.pdf"
			(at 121.92 50.8 0)
			(effects
				(font
					(size 1.27 1.27)
					(thickness 0.15)
				)
				(justify left bottom)
				(hide yes)
			)
		)
		(property "Description" ""
			(at 68.58 33.02 0)
			(effects
				(font
					(size 1.27 1.27)
				)
				(hide yes)
			)
		)
		(property "Author" "Antmicro"
			(at 121.92 53.34 0)
			(effects
				(font
					(size 1.27 1.27)
					(thickness 0.15)
				)
				(justify left bottom)
				(hide yes)
			)
		)
		(property "License" "Apache-2.0"
			(at 121.92 55.88 0)
			(effects
				(font
					(size 1.27 1.27)
					(thickness 0.15)
				)
				(justify left bottom)
				(hide yes)
			)
		)
		(property "Manufacturer" "ept"
			(at 121.92 38.1 0)
			(effects
				(font
					(size 1.27 1.27)
					(thickness 0.15)
				)
				(justify left bottom)
				(hide yes)
			)
		)
		(property "MPN" "401-51501-51"
			(at 49.53 27.94 0)
			(effects
				(font
					(size 1.27 1.27)
					(thickness 0.15)
				)
			)
		)
		(pin "C91"
		)
		(pin "C92"
		)
		(pin "A15"
		)
		(pin "A91"
		)
		(pin "C34"
		)
		(pin "C35"
		)
		(pin "D22"
		)
		(pin "D23"
		)
		(pin "D55"
		)
		(pin "D56"
		)
		(pin "C55"
		)
		(pin "C56"
		)
		(pin "C71"
		)
		(pin "C72"
		)
		(pin "C32"
		)
		(pin "C33"
		)
		(pin "B6"
		)
		(pin "B58"
		)
		(pin "B59"
		)
		(pin "D5"
		)
		(pin "D51"
		)
		(pin "A29"
		)
		(pin "D46"
		)
		(pin "D47"
		)
		(pin "C105"
		)
		(pin "C106"
		)
		(pin "A16"
		)
		(pin "B22"
		)
		(pin "B51"
		)
		(pin "B30"
		)
		(pin "A44"
		)
		(pin "C51"
		)
		(pin "C60"
		)
		(pin "A81"
		)
		(pin "A82"
		)
		(pin "D90"
		)
		(pin "D93"
		)
		(pin "B68"
		)
		(pin "B69"
		)
		(pin "C103"
		)
		(pin "C104"
		)
		(pin "C58"
		)
		(pin "C59"
		)
		(pin "D84"
		)
		(pin "D87"
		)
		(pin "A30"
		)
		(pin "B29"
		)
		(pin "A41"
		)
		(pin "C40"
		)
		(pin "C42"
		)
		(pin "D80"
		)
		(pin "D83"
		)
		(pin "B103"
		)
		(pin "A102"
		)
		(pin "C101"
		)
		(pin "C102"
		)
		(pin "D11"
		)
		(pin "D110"
		)
		(pin "B37"
		)
		(pin "B45"
		)
		(pin "C61"
		)
		(pin "C62"
		)
		(pin "A42"
		)
		(pin "B36"
		)
		(pin "B57"
		)
		(pin "D12"
		)
		(pin "D44"
		)
		(pin "D48"
		)
		(pin "B32"
		)
		(pin "B107"
		)
		(pin "B108"
		)
		(pin "B110"
		)
		(pin "B101"
		)
		(pin "C63"
		)
		(pin "C64"
		)
		(pin "B50"
		)
		(pin "A87"
		)
		(pin "A86"
		)
		(pin "B27"
		)
		(pin "D17"
		)
		(pin "D24"
		)
		(pin "D26"
		)
		(pin "D27"
		)
		(pin "A47"
		)
		(pin "C81"
		)
		(pin "C82"
		)
		(pin "C68"
		)
		(pin "C69"
		)
		(pin "A74"
		)
		(pin "A48"
		)
		(pin "A57"
		)
		(pin "A43"
		)
		(pin "A31"
		)
		(pin "D29"
		)
		(pin "D30"
		)
		(pin "C36"
		)
		(pin "C37"
		)
		(pin "C3"
		)
		(pin "A35"
		)
		(pin "A34"
		)
		(pin "B7"
		)
		(pin "B46"
		)
		(pin "B1"
		)
		(pin "B63"
		)
		(pin "A51"
		)
		(pin "A99"
		)
		(pin "B17"
		)
		(pin "C13"
		)
		(pin "C4"
		)
		(pin "B102"
		)
		(pin "C38"
		)
		(pin "C39"
		)
		(pin "B3"
		)
		(pin "A90"
		)
		(pin "A72"
		)
		(pin "B84"
		)
		(pin "D19"
		)
		(pin "D20"
		)
		(pin "D43"
		)
		(pin "D45"
		)
		(pin "A77"
		)
		(pin "A78"
		)
		(pin "B38"
		)
		(pin "B86"
		)
		(pin "D77"
		)
		(pin "D8"
		)
		(pin "A32"
		)
		(pin "B85"
		)
		(pin "D73"
		)
		(pin "D76"
		)
		(pin "D63"
		)
		(pin "D64"
		)
		(pin "D67"
		)
		(pin "D70"
		)
		(pin "B83"
		)
		(pin "D81"
		)
		(pin "D82"
		)
		(pin "B41"
		)
		(pin "D49"
		)
		(pin "D50"
		)
		(pin "A75"
		)
		(pin "D2"
		)
		(pin "D21"
		)
		(pin "C78"
		)
		(pin "C79"
		)
		(pin "B19"
		)
		(pin "B39"
		)
		(pin "A12"
		)
		(pin "B66"
		)
		(pin "D4"
		)
		(pin "D85"
		)
		(pin "D86"
		)
		(pin "A105"
		)
		(pin "B90"
		)
		(pin "A22"
		)
		(pin "A109"
		)
		(pin "B88"
		)
		(pin "B14"
		)
		(pin "B71"
		)
		(pin "B52"
		)
		(pin "B53"
		)
		(pin "D7"
		)
		(pin "A108"
		)
		(pin "C85"
		)
		(pin "C86"
		)
		(pin "B61"
		)
		(pin "B62"
		)
		(pin "D68"
		)
		(pin "D69"
		)
		(pin "A88"
		)
		(pin "A89"
		)
		(pin "D6"
		)
		(pin "C7"
		)
		(pin "B33"
		)
		(pin "D88"
		)
		(pin "D89"
		)
		(pin "B26"
		)
		(pin "A76"
		)
		(pin "D101"
		)
		(pin "D102"
		)
		(pin "B12"
		)
		(pin "C15"
		)
		(pin "C16"
		)
		(pin "A18"
		)
		(pin "A13"
		)
		(pin "A66"
		)
		(pin "C26"
		)
		(pin "C27"
		)
		(pin "A101"
		)
		(pin "A17"
		)
		(pin "B96"
		)
		(pin "C22"
		)
		(pin "C23"
		)
		(pin "A79"
		)
		(pin "A54"
		)
		(pin "C41"
		)
		(pin "C44"
		)
		(pin "A100"
		)
		(pin "A67"
		)
		(pin "A10"
		)
		(pin "A14"
		)
		(pin "C6"
		)
		(pin "A84"
		)
		(pin "B91"
		)
		(pin "C29"
		)
		(pin "C30"
		)
		(pin "A37"
		)
		(pin "A39"
		)
		(pin "B10"
		)
		(pin "B34"
		)
		(pin "C54"
		)
		(pin "C57"
		)
		(pin "B64"
		)
		(pin "B65"
		)
		(pin "A58"
		)
		(pin "A59"
		)
		(pin "B92"
		)
		(pin "C43"
		)
		(pin "C45"
		)
		(pin "A97"
		)
		(pin "A11"
		)
		(pin "A61"
		)
		(pin "A62"
		)
		(pin "B48"
		)
		(pin "B54"
		)
		(pin "D71"
		)
		(pin "D72"
		)
		(pin "A26"
		)
		(pin "A36"
		)
		(pin "D31"
		)
		(pin "D36"
		)
		(pin "B76"
		)
		(pin "B21"
		)
		(pin "B24"
		)
		(pin "B94"
		)
		(pin "D3"
		)
		(pin "B79"
		)
		(pin "A85"
		)
		(pin "A23"
		)
		(pin "A25"
		)
		(pin "A24"
		)
		(pin "D14"
		)
		(pin "D18"
		)
		(pin "B15"
		)
		(pin "A107"
		)
		(pin "A98"
		)
		(pin "D9"
		)
		(pin "B44"
		)
		(pin "A4"
		)
		(pin "C28"
		)
		(pin "C31"
		)
		(pin "A9"
		)
		(pin "C49"
		)
		(pin "C50"
		)
		(pin "A83"
		)
		(pin "A110"
		)
		(pin "D52"
		)
		(pin "D53"
		)
		(pin "A40"
		)
		(pin "A71"
		)
		(pin "D98"
		)
		(pin "D99"
		)
		(pin "D40"
		)
		(pin "D42"
		)
		(pin "D37"
		)
		(pin "D41"
		)
		(pin "C109"
		)
		(pin "C11"
		)
		(pin "A106"
		)
		(pin "A3"
		)
		(pin "B109"
		)
		(pin "B40"
		)
		(pin "C70"
		)
		(pin "C73"
		)
		(pin "D13"
		)
		(pin "A1"
		)
		(pin "A46"
		)
		(pin "A20"
		)
		(pin "A104"
		)
		(pin "C9"
		)
		(pin "C110"
		)
		(pin "C14"
		)
		(pin "B23"
		)
		(pin "A93"
		)
		(pin "B89"
		)
		(pin "B87"
		)
		(pin "D54"
		)
		(pin "D60"
		)
		(pin "A21"
		)
		(pin "B93"
		)
		(pin "A70"
		)
		(pin "A60"
		)
		(pin "B97"
		)
		(pin "B95"
		)
		(pin "D38"
		)
		(pin "D39"
		)
		(pin "A50"
		)
		(pin "A52"
		)
		(pin "A53"
		)
		(pin "D91"
		)
		(pin "D92"
		)
		(pin "C67"
		)
		(pin "D57"
		)
		(pin "A96"
		)
		(pin "A92"
		)
		(pin "B70"
		)
		(pin "C46"
		)
		(pin "C47"
		)
		(pin "B4"
		)
		(pin "A64"
		)
		(pin "A65"
		)
		(pin "B43"
		)
		(pin "C21"
		)
		(pin "C25"
		)
		(pin "B42"
		)
		(pin "C19"
		)
		(pin "C20"
		)
		(pin "C18"
		)
		(pin "C2"
		)
		(pin "C107"
		)
		(pin "C108"
		)
		(pin "B35"
		)
		(pin "A28"
		)
		(pin "B11"
		)
		(pin "A103"
		)
		(pin "C97"
		)
		(pin "D1"
		)
		(pin "B98"
		)
		(pin "A19"
		)
		(pin "A68"
		)
		(pin "A69"
		)
		(pin "B55"
		)
		(pin "B56"
		)
		(pin "A8"
		)
		(pin "A33"
		)
		(pin "A95"
		)
		(pin "D96"
		)
		(pin "D97"
		)
		(pin "B31"
		)
		(pin "B105"
		)
		(pin "B100"
		)
		(pin "C65"
		)
		(pin "C66"
		)
		(pin "B104"
		)
		(pin "D61"
		)
		(pin "D62"
		)
		(pin "D78"
		)
		(pin "D79"
		)
		(pin "C83"
		)
		(pin "C84"
		)
		(pin "D74"
		)
		(pin "D75"
		)
		(pin "A45"
		)
		(pin "D106"
		)
		(pin "D107"
		)
		(pin "C8"
		)
		(pin "C80"
		)
		(pin "C87"
		)
		(pin "C90"
		)
		(pin "D58"
		)
		(pin "D59"
		)
		(pin "D104"
		)
		(pin "D105"
		)
		(pin "C93"
		)
		(pin "C96"
		)
		(pin "B73"
		)
		(pin "D108"
		)
		(pin "D109"
		)
		(pin "B20"
		)
		(pin "A27"
		)
		(pin "D34"
		)
		(pin "D35"
		)
		(pin "C17"
		)
		(pin "C24"
		)
		(pin "B49"
		)
		(pin "A6"
		)
		(pin "B5"
		)
		(pin "B99"
		)
		(pin "B25"
		)
		(pin "D94"
		)
		(pin "D95"
		)
		(pin "B106"
		)
		(pin "B67"
		)
		(pin "A2"
		)
		(pin "B13"
		)
		(pin "A49"
		)
		(pin "C52"
		)
		(pin "C53"
		)
		(pin "B72"
		)
		(pin "C94"
		)
		(pin "C95"
		)
		(pin "B74"
		)
		(pin "D10"
		)
		(pin "B75"
		)
		(pin "B77"
		)
		(pin "C98"
		)
		(pin "C99"
		)
		(pin "A7"
		)
		(pin "C88"
		)
		(pin "C89"
		)
		(pin "C10"
		)
		(pin "B78"
		)
		(pin "B81"
		)
		(pin "B28"
		)
		(pin "A63"
		)
		(pin "C76"
		)
		(pin "C77"
		)
		(pin "A55"
		)
		(pin "A56"
		)
		(pin "C48"
		)
		(pin "C5"
		)
		(pin "A5"
		)
		(pin "C1"
		)
		(pin "C100"
		)
		(pin "B47"
		)
		(pin "C74"
		)
		(pin "C75"
		)
		(pin "C12"
		)
		(pin "B80"
		)
		(pin "D15"
		)
		(pin "D16"
		)
		(pin "D100"
		)
		(pin "D103"
		)
		(pin "B2"
		)
		(pin "B9"
		)
		(pin "A94"
		)
		(pin "B82"
		)
		(pin "D25"
		)
		(pin "D28"
		)
		(pin "B16"
		)
		(pin "D65"
		)
		(pin "D66"
		)
		(pin "D32"
		)
		(pin "D33"
		)
		(pin "B8"
		)
		(pin "B60"
		)
		(pin "A38"
		)
		(pin "A73"
		)
		(pin "A80"
		)
		(pin "B18"
		)
		(pin "MP"
		)
		(instances
			(project "com-express-7-baseboard"
				(path ""
					(reference "J12")
					(unit 14)
				)
			)
		)
	)
	(symbol
		(lib_id "antmicroMechanicalParts:Spacer_Drill3.7mm_H5mm_9774050151R")
		(at 247.65 246.38 0)
		(unit 1)
		(exclude_from_sim no)
		(in_bom yes)
		(on_board yes)
		(dnp no)
		(fields_autoplaced yes)
		(property "Reference" "H6"
			(at 256.54 245.11 0)
			(effects
				(font
					(size 1.27 1.27)
					(thickness 0.15)
				)
				(justify left)
			)
		)
		(property "Value" "Spacer_Drill3.7mm_H5mm_9774050151R"
			(at 256.54 247.65 0)
			(effects
				(font
					(size 1.27 1.27)
					(thickness 0.15)
				)
				(justify left)
			)
		)
		(property "Footprint" "antmicro-footprints:Spacer_Drill3.7mm_H5mm_9774050151R"
			(at 270.51 254 0)
			(effects
				(font
					(size 1.27 1.27)
					(thickness 0.15)
				)
				(justify left bottom)
				(hide yes)
			)
		)
		(property "Datasheet" "https://www.we-online.com/catalog/datasheet/9774050151.pdf"
			(at 270.51 256.54 0)
			(effects
				(font
					(size 1.27 1.27)
					(thickness 0.15)
				)
				(justify left bottom)
				(hide yes)
			)
		)
		(property "Description" ""
			(at 247.65 246.38 0)
			(effects
				(font
					(size 1.27 1.27)
				)
				(hide yes)
			)
		)
		(property "Manufacturer" "Würth Elektronik"
			(at 270.51 259.08 0)
			(effects
				(font
					(size 1.27 1.27)
					(thickness 0.15)
				)
				(justify left bottom)
				(hide yes)
			)
		)
		(property "MPN" "9774050151R"
			(at 270.51 261.62 0)
			(effects
				(font
					(size 1.27 1.27)
					(thickness 0.15)
				)
				(justify left bottom)
				(hide yes)
			)
		)
		(property "Author" "Antmicro"
			(at 270.51 264.16 0)
			(effects
				(font
					(size 1.27 1.27)
					(thickness 0.15)
				)
				(justify left bottom)
				(hide yes)
			)
		)
		(property "License" "Apache-2.0"
			(at 270.51 266.7 0)
			(effects
				(font
					(size 1.27 1.27)
					(thickness 0.15)
				)
				(justify left bottom)
				(hide yes)
			)
		)
		(pin "1"
		)
		(instances
			(project "com-express-7-baseboard"
				(path ""
					(reference "H6")
					(unit 1)
				)
			)
		)
	)
	(symbol
		(lib_id "antmicroMechanicalParts:Spacer_Drill3.7mm_H5mm_9774050151R")
		(at 247.65 259.08 0)
		(unit 1)
		(exclude_from_sim no)
		(in_bom yes)
		(on_board yes)
		(dnp no)
		(fields_autoplaced yes)
		(property "Reference" "H8"
			(at 256.54 257.81 0)
			(effects
				(font
					(size 1.27 1.27)
					(thickness 0.15)
				)
				(justify left)
			)
		)
		(property "Value" "Spacer_Drill3.7mm_H5mm_9774050151R"
			(at 256.54 260.35 0)
			(effects
				(font
					(size 1.27 1.27)
					(thickness 0.15)
				)
				(justify left)
			)
		)
		(property "Footprint" "antmicro-footprints:Spacer_Drill3.7mm_H5mm_9774050151R"
			(at 270.51 266.7 0)
			(effects
				(font
					(size 1.27 1.27)
					(thickness 0.15)
				)
				(justify left bottom)
				(hide yes)
			)
		)
		(property "Datasheet" "https://www.we-online.com/catalog/datasheet/9774050151.pdf"
			(at 270.51 269.24 0)
			(effects
				(font
					(size 1.27 1.27)
					(thickness 0.15)
				)
				(justify left bottom)
				(hide yes)
			)
		)
		(property "Description" ""
			(at 247.65 259.08 0)
			(effects
				(font
					(size 1.27 1.27)
				)
				(hide yes)
			)
		)
		(property "Manufacturer" "Würth Elektronik"
			(at 270.51 271.78 0)
			(effects
				(font
					(size 1.27 1.27)
					(thickness 0.15)
				)
				(justify left bottom)
				(hide yes)
			)
		)
		(property "MPN" "9774050151R"
			(at 270.51 274.32 0)
			(effects
				(font
					(size 1.27 1.27)
					(thickness 0.15)
				)
				(justify left bottom)
				(hide yes)
			)
		)
		(property "Author" "Antmicro"
			(at 270.51 276.86 0)
			(effects
				(font
					(size 1.27 1.27)
					(thickness 0.15)
				)
				(justify left bottom)
				(hide yes)
			)
		)
		(property "License" "Apache-2.0"
			(at 270.51 279.4 0)
			(effects
				(font
					(size 1.27 1.27)
					(thickness 0.15)
				)
				(justify left bottom)
				(hide yes)
			)
		)
		(pin "1"
		)
		(instances
			(project "com-express-7-baseboard"
				(path ""
					(reference "H8")
					(unit 1)
				)
			)
		)
	)
	(symbol
		(lib_id "antmicroTestPoints:TP_0.75mm_SMD")
		(at 213.36 187.96 0)
		(unit 1)
		(exclude_from_sim no)
		(in_bom no)
		(on_board yes)
		(dnp no)
		(fields_autoplaced yes)
		(property "Reference" "TP16"
			(at 218.44 187.96 0)
			(effects
				(font
					(size 1.27 1.27)
					(thickness 0.15)
				)
				(justify left)
			)
		)
		(property "Value" "TP_0.75mm_SMD"
			(at 224.155 191.77 0)
			(effects
				(font
					(size 1.27 1.27)
					(thickness 0.15)
				)
				(justify left bottom)
				(hide yes)
			)
		)
		(property "Footprint" "antmicro-footprints:TP_SMD_0.75mm"
			(at 224.155 194.31 0)
			(effects
				(font
					(size 1.27 1.27)
					(thickness 0.15)
				)
				(justify left bottom)
				(hide yes)
			)
		)
		(property "Datasheet" ""
			(at 231.14 200.66 0)
			(effects
				(font
					(size 1.27 1.27)
					(thickness 0.15)
				)
				(justify left bottom)
				(hide yes)
			)
		)
		(property "Description" ""
			(at 213.36 187.96 0)
			(effects
				(font
					(size 1.27 1.27)
				)
				(hide yes)
			)
		)
		(property "MPN" ""
			(at 224.155 199.39 0)
			(effects
				(font
					(size 1.27 1.27)
					(thickness 0.15)
				)
				(justify left bottom)
				(hide yes)
			)
		)
		(property "Manufacturer" ""
			(at 224.155 194.31 0)
			(effects
				(font
					(size 1.27 1.27)
					(thickness 0.15)
				)
				(justify left bottom)
				(hide yes)
			)
		)
		(property "Author" "Antmicro"
			(at 224.155 196.85 0)
			(effects
				(font
					(size 1.27 1.27)
					(thickness 0.15)
				)
				(justify left bottom)
				(hide yes)
			)
		)
		(property "License" "Apache-2.0"
			(at 224.155 199.39 0)
			(effects
				(font
					(size 1.27 1.27)
					(thickness 0.15)
				)
				(justify left bottom)
				(hide yes)
			)
		)
		(property "Public" "False"
			(at 223.52 201.93 0)
			(effects
				(font
					(size 1.27 1.27)
				)
				(justify left bottom)
				(hide yes)
			)
		)
		(pin "1"
		)
		(instances
			(project "com-express-7-baseboard"
				(path ""
					(reference "TP16")
					(unit 1)
				)
			)
		)
	)
	(symbol
		(lib_id "antmicroB2BConnectors:Plug_Bus_CE7_EPT_401-51501-51")
		(at 210.82 33.02 0)
		(unit 16)
		(exclude_from_sim no)
		(in_bom yes)
		(on_board yes)
		(dnp no)
		(fields_autoplaced yes)
		(property "Reference" "J12"
			(at 191.77 25.4 0)
			(effects
				(font
					(size 1.27 1.27)
					(thickness 0.15)
				)
			)
		)
		(property "Value" "Plug_Bus_CE7_EPT_401-51501-51"
			(at 264.16 45.72 0)
			(effects
				(font
					(size 1.27 1.27)
					(thickness 0.15)
				)
				(justify left bottom)
				(hide yes)
			)
		)
		(property "Footprint" "antmicro-footprints:EPT_401-51501-51"
			(at 264.16 48.26 0)
			(effects
				(font
					(size 1.27 1.27)
					(thickness 0.15)
				)
				(justify left bottom)
				(hide yes)
			)
		)
		(property "Datasheet" "https://www.farnell.com/datasheets/1905093.pdf"
			(at 264.16 50.8 0)
			(effects
				(font
					(size 1.27 1.27)
					(thickness 0.15)
				)
				(justify left bottom)
				(hide yes)
			)
		)
		(property "Description" ""
			(at 210.82 33.02 0)
			(effects
				(font
					(size 1.27 1.27)
				)
				(hide yes)
			)
		)
		(property "Author" "Antmicro"
			(at 264.16 53.34 0)
			(effects
				(font
					(size 1.27 1.27)
					(thickness 0.15)
				)
				(justify left bottom)
				(hide yes)
			)
		)
		(property "License" "Apache-2.0"
			(at 264.16 55.88 0)
			(effects
				(font
					(size 1.27 1.27)
					(thickness 0.15)
				)
				(justify left bottom)
				(hide yes)
			)
		)
		(property "Manufacturer" "ept"
			(at 264.16 38.1 0)
			(effects
				(font
					(size 1.27 1.27)
					(thickness 0.15)
				)
				(justify left bottom)
				(hide yes)
			)
		)
		(property "MPN" "401-51501-51"
			(at 191.77 27.94 0)
			(effects
				(font
					(size 1.27 1.27)
					(thickness 0.15)
				)
			)
		)
		(pin "C91"
		)
		(pin "C92"
		)
		(pin "A15"
		)
		(pin "A91"
		)
		(pin "C34"
		)
		(pin "C35"
		)
		(pin "D22"
		)
		(pin "D23"
		)
		(pin "D55"
		)
		(pin "D56"
		)
		(pin "C55"
		)
		(pin "C56"
		)
		(pin "C71"
		)
		(pin "C72"
		)
		(pin "C32"
		)
		(pin "C33"
		)
		(pin "B6"
		)
		(pin "B58"
		)
		(pin "B59"
		)
		(pin "D5"
		)
		(pin "D51"
		)
		(pin "A29"
		)
		(pin "D46"
		)
		(pin "D47"
		)
		(pin "C105"
		)
		(pin "C106"
		)
		(pin "A16"
		)
		(pin "B22"
		)
		(pin "B51"
		)
		(pin "B30"
		)
		(pin "A44"
		)
		(pin "C51"
		)
		(pin "C60"
		)
		(pin "A81"
		)
		(pin "A82"
		)
		(pin "D90"
		)
		(pin "D93"
		)
		(pin "B68"
		)
		(pin "B69"
		)
		(pin "C103"
		)
		(pin "C104"
		)
		(pin "C58"
		)
		(pin "C59"
		)
		(pin "D84"
		)
		(pin "D87"
		)
		(pin "A30"
		)
		(pin "B29"
		)
		(pin "A41"
		)
		(pin "C40"
		)
		(pin "C42"
		)
		(pin "D80"
		)
		(pin "D83"
		)
		(pin "B103"
		)
		(pin "A102"
		)
		(pin "C101"
		)
		(pin "C102"
		)
		(pin "D11"
		)
		(pin "D110"
		)
		(pin "B37"
		)
		(pin "B45"
		)
		(pin "C61"
		)
		(pin "C62"
		)
		(pin "A42"
		)
		(pin "B36"
		)
		(pin "B57"
		)
		(pin "D12"
		)
		(pin "D44"
		)
		(pin "D48"
		)
		(pin "B32"
		)
		(pin "B107"
		)
		(pin "B108"
		)
		(pin "B110"
		)
		(pin "B101"
		)
		(pin "C63"
		)
		(pin "C64"
		)
		(pin "B50"
		)
		(pin "A87"
		)
		(pin "A86"
		)
		(pin "B27"
		)
		(pin "D17"
		)
		(pin "D24"
		)
		(pin "D26"
		)
		(pin "D27"
		)
		(pin "A47"
		)
		(pin "C81"
		)
		(pin "C82"
		)
		(pin "C68"
		)
		(pin "C69"
		)
		(pin "A74"
		)
		(pin "A48"
		)
		(pin "A57"
		)
		(pin "A43"
		)
		(pin "A31"
		)
		(pin "D29"
		)
		(pin "D30"
		)
		(pin "C36"
		)
		(pin "C37"
		)
		(pin "C3"
		)
		(pin "A35"
		)
		(pin "A34"
		)
		(pin "B7"
		)
		(pin "B46"
		)
		(pin "B1"
		)
		(pin "B63"
		)
		(pin "A51"
		)
		(pin "A99"
		)
		(pin "B17"
		)
		(pin "C13"
		)
		(pin "C4"
		)
		(pin "B102"
		)
		(pin "C38"
		)
		(pin "C39"
		)
		(pin "B3"
		)
		(pin "A90"
		)
		(pin "A72"
		)
		(pin "B84"
		)
		(pin "D19"
		)
		(pin "D20"
		)
		(pin "D43"
		)
		(pin "D45"
		)
		(pin "A77"
		)
		(pin "A78"
		)
		(pin "B38"
		)
		(pin "B86"
		)
		(pin "D77"
		)
		(pin "D8"
		)
		(pin "A32"
		)
		(pin "B85"
		)
		(pin "D73"
		)
		(pin "D76"
		)
		(pin "D63"
		)
		(pin "D64"
		)
		(pin "D67"
		)
		(pin "D70"
		)
		(pin "B83"
		)
		(pin "D81"
		)
		(pin "D82"
		)
		(pin "B41"
		)
		(pin "D49"
		)
		(pin "D50"
		)
		(pin "A75"
		)
		(pin "D2"
		)
		(pin "D21"
		)
		(pin "C78"
		)
		(pin "C79"
		)
		(pin "B19"
		)
		(pin "B39"
		)
		(pin "A12"
		)
		(pin "B66"
		)
		(pin "D4"
		)
		(pin "D85"
		)
		(pin "D86"
		)
		(pin "A105"
		)
		(pin "B90"
		)
		(pin "A22"
		)
		(pin "A109"
		)
		(pin "B88"
		)
		(pin "B14"
		)
		(pin "B71"
		)
		(pin "B52"
		)
		(pin "B53"
		)
		(pin "D7"
		)
		(pin "A108"
		)
		(pin "C85"
		)
		(pin "C86"
		)
		(pin "B61"
		)
		(pin "B62"
		)
		(pin "D68"
		)
		(pin "D69"
		)
		(pin "A88"
		)
		(pin "A89"
		)
		(pin "D6"
		)
		(pin "C7"
		)
		(pin "B33"
		)
		(pin "D88"
		)
		(pin "D89"
		)
		(pin "B26"
		)
		(pin "A76"
		)
		(pin "D101"
		)
		(pin "D102"
		)
		(pin "B12"
		)
		(pin "C15"
		)
		(pin "C16"
		)
		(pin "A18"
		)
		(pin "A13"
		)
		(pin "A66"
		)
		(pin "C26"
		)
		(pin "C27"
		)
		(pin "A101"
		)
		(pin "A17"
		)
		(pin "B96"
		)
		(pin "C22"
		)
		(pin "C23"
		)
		(pin "A79"
		)
		(pin "A54"
		)
		(pin "C41"
		)
		(pin "C44"
		)
		(pin "A100"
		)
		(pin "A67"
		)
		(pin "A10"
		)
		(pin "A14"
		)
		(pin "C6"
		)
		(pin "A84"
		)
		(pin "B91"
		)
		(pin "C29"
		)
		(pin "C30"
		)
		(pin "A37"
		)
		(pin "A39"
		)
		(pin "B10"
		)
		(pin "B34"
		)
		(pin "C54"
		)
		(pin "C57"
		)
		(pin "B64"
		)
		(pin "B65"
		)
		(pin "A58"
		)
		(pin "A59"
		)
		(pin "B92"
		)
		(pin "C43"
		)
		(pin "C45"
		)
		(pin "A97"
		)
		(pin "A11"
		)
		(pin "A61"
		)
		(pin "A62"
		)
		(pin "B48"
		)
		(pin "B54"
		)
		(pin "D71"
		)
		(pin "D72"
		)
		(pin "A26"
		)
		(pin "A36"
		)
		(pin "D31"
		)
		(pin "D36"
		)
		(pin "B76"
		)
		(pin "B21"
		)
		(pin "B24"
		)
		(pin "B94"
		)
		(pin "D3"
		)
		(pin "B79"
		)
		(pin "A85"
		)
		(pin "A23"
		)
		(pin "A25"
		)
		(pin "A24"
		)
		(pin "D14"
		)
		(pin "D18"
		)
		(pin "B15"
		)
		(pin "A107"
		)
		(pin "A98"
		)
		(pin "D9"
		)
		(pin "B44"
		)
		(pin "A4"
		)
		(pin "C28"
		)
		(pin "C31"
		)
		(pin "A9"
		)
		(pin "C49"
		)
		(pin "C50"
		)
		(pin "A83"
		)
		(pin "A110"
		)
		(pin "D52"
		)
		(pin "D53"
		)
		(pin "A40"
		)
		(pin "A71"
		)
		(pin "D98"
		)
		(pin "D99"
		)
		(pin "D40"
		)
		(pin "D42"
		)
		(pin "D37"
		)
		(pin "D41"
		)
		(pin "C109"
		)
		(pin "C11"
		)
		(pin "A106"
		)
		(pin "A3"
		)
		(pin "B109"
		)
		(pin "B40"
		)
		(pin "C70"
		)
		(pin "C73"
		)
		(pin "D13"
		)
		(pin "A1"
		)
		(pin "A46"
		)
		(pin "A20"
		)
		(pin "A104"
		)
		(pin "C9"
		)
		(pin "C110"
		)
		(pin "C14"
		)
		(pin "B23"
		)
		(pin "A93"
		)
		(pin "B89"
		)
		(pin "B87"
		)
		(pin "D54"
		)
		(pin "D60"
		)
		(pin "A21"
		)
		(pin "B93"
		)
		(pin "A70"
		)
		(pin "A60"
		)
		(pin "B97"
		)
		(pin "B95"
		)
		(pin "D38"
		)
		(pin "D39"
		)
		(pin "A50"
		)
		(pin "A52"
		)
		(pin "A53"
		)
		(pin "D91"
		)
		(pin "D92"
		)
		(pin "C67"
		)
		(pin "D57"
		)
		(pin "A96"
		)
		(pin "A92"
		)
		(pin "B70"
		)
		(pin "C46"
		)
		(pin "C47"
		)
		(pin "B4"
		)
		(pin "A64"
		)
		(pin "A65"
		)
		(pin "B43"
		)
		(pin "C21"
		)
		(pin "C25"
		)
		(pin "B42"
		)
		(pin "C19"
		)
		(pin "C20"
		)
		(pin "C18"
		)
		(pin "C2"
		)
		(pin "C107"
		)
		(pin "C108"
		)
		(pin "B35"
		)
		(pin "A28"
		)
		(pin "B11"
		)
		(pin "A103"
		)
		(pin "C97"
		)
		(pin "D1"
		)
		(pin "B98"
		)
		(pin "A19"
		)
		(pin "A68"
		)
		(pin "A69"
		)
		(pin "B55"
		)
		(pin "B56"
		)
		(pin "A8"
		)
		(pin "A33"
		)
		(pin "A95"
		)
		(pin "D96"
		)
		(pin "D97"
		)
		(pin "B31"
		)
		(pin "B105"
		)
		(pin "B100"
		)
		(pin "C65"
		)
		(pin "C66"
		)
		(pin "B104"
		)
		(pin "D61"
		)
		(pin "D62"
		)
		(pin "D78"
		)
		(pin "D79"
		)
		(pin "C83"
		)
		(pin "C84"
		)
		(pin "D74"
		)
		(pin "D75"
		)
		(pin "A45"
		)
		(pin "D106"
		)
		(pin "D107"
		)
		(pin "C8"
		)
		(pin "C80"
		)
		(pin "C87"
		)
		(pin "C90"
		)
		(pin "D58"
		)
		(pin "D59"
		)
		(pin "D104"
		)
		(pin "D105"
		)
		(pin "C93"
		)
		(pin "C96"
		)
		(pin "B73"
		)
		(pin "D108"
		)
		(pin "D109"
		)
		(pin "B20"
		)
		(pin "A27"
		)
		(pin "D34"
		)
		(pin "D35"
		)
		(pin "C17"
		)
		(pin "C24"
		)
		(pin "B49"
		)
		(pin "A6"
		)
		(pin "B5"
		)
		(pin "B99"
		)
		(pin "B25"
		)
		(pin "D94"
		)
		(pin "D95"
		)
		(pin "B106"
		)
		(pin "B67"
		)
		(pin "A2"
		)
		(pin "B13"
		)
		(pin "A49"
		)
		(pin "C52"
		)
		(pin "C53"
		)
		(pin "B72"
		)
		(pin "C94"
		)
		(pin "C95"
		)
		(pin "B74"
		)
		(pin "D10"
		)
		(pin "B75"
		)
		(pin "B77"
		)
		(pin "C98"
		)
		(pin "C99"
		)
		(pin "A7"
		)
		(pin "C88"
		)
		(pin "C89"
		)
		(pin "C10"
		)
		(pin "B78"
		)
		(pin "B81"
		)
		(pin "B28"
		)
		(pin "A63"
		)
		(pin "C76"
		)
		(pin "C77"
		)
		(pin "A55"
		)
		(pin "A56"
		)
		(pin "C48"
		)
		(pin "C5"
		)
		(pin "A5"
		)
		(pin "C1"
		)
		(pin "C100"
		)
		(pin "B47"
		)
		(pin "C74"
		)
		(pin "C75"
		)
		(pin "C12"
		)
		(pin "B80"
		)
		(pin "D15"
		)
		(pin "D16"
		)
		(pin "D100"
		)
		(pin "D103"
		)
		(pin "B2"
		)
		(pin "B9"
		)
		(pin "A94"
		)
		(pin "B82"
		)
		(pin "D25"
		)
		(pin "D28"
		)
		(pin "B16"
		)
		(pin "D65"
		)
		(pin "D66"
		)
		(pin "D32"
		)
		(pin "D33"
		)
		(pin "B8"
		)
		(pin "B60"
		)
		(pin "A38"
		)
		(pin "A73"
		)
		(pin "A80"
		)
		(pin "B18"
		)
		(pin "MP"
		)
		(instances
			(project "com-express-7-baseboard"
				(path ""
					(reference "J12")
					(unit 16)
				)
			)
		)
	)
)
